FILE_TYPE = MACRO_DRAWING;
SET COLOR_WIRE YELLOW;
SET COLOR_PROP MONO;
SET COLOR_DOT WHITE;
SET COLOR_ARC YELLOW;
SET COLOR_BODY GREEN;
SET COLOR_NOTE MONO;
SET PROP_DISPLAY VALUE;
SET PAGE_NUMBER P130;
FORCEADD CAP_A..1
(1925 1600);
FORCEPROP 1 LAST LOCATION C2N20
J 0
(1975 1700);
DISPLAY 0.617021 (1975 1700);
PAINT AQUA (1975 1700);
FORCEPROP 1 LAST PART_NUMBER D97712-004
J 0
(1975 1450);
DISPLAY 0.617021 (1975 1450);
PAINT BLUE (1975 1450);
FORCEPROP 1 LAST VALUE 1.0UF
J 0
(1975 1650);
DISPLAY 0.617021 (1975 1650);
PAINT SKYBLUE (1975 1650);
FORCEPROP 1 LAST TOLERANCE 10%
J 0
(1975 1550);
DISPLAY 0.617021 (1975 1550);
PAINT SKYBLUE (1975 1550);
FORCEPROP 1 LAST PACK_TYPE 0402V
J 0
(1975 1400);
DISPLAY 0.617021 (1975 1400);
PAINT SKYBLUE (1975 1400);
FORCEPROP 1 LAST VOLTAGE 6.3V
J 0
(1975 1600);
DISPLAY 0.617021 (1975 1600);
PAINT SKYBLUE (1975 1600);
FORCEPROP 1 LAST MATERIAL X6S
J 0
(1975 1500);
DISPLAY 0.617021 (1975 1500);
PAINT SKYBLUE (1975 1500);
FORCEPROP 1 LASTPIN (1925 1700) $PN 1
J 0
(1935 1680);
DISPLAY 0.617021 (1935 1680);
PAINT WHITE (1935 1680);
FORCEPROP 1 LASTPIN (1925 1500) $PN 2
J 0
(1935 1480);
DISPLAY 0.617021 (1935 1480);
PAINT WHITE (1935 1480);
FORCEPROP 2 LAST CDS_LOCATION C2N20
J 0
(1975 1700);
DISPLAY 0.617021 (1975 1700);
PAINT AQUA (1975 1700);
DISPLAY INVISIBLE (1975 1700);
FORCEPROP 2 LAST BOM_COST SB
J 0
(1975 1350);
PAINT MONO (1975 1350);
DISPLAY INVISIBLE (1975 1350);
FORCEPROP 2 LAST CDS_LIB dev_discrete
J 0
(1925 1600);
PAINT ORANGE (1925 1600);
DISPLAY INVISIBLE (1925 1600);
FORCEPROP 2 LAST CDS_SEC 1
J 0
(1975 1800);
DISPLAY 1.361702 (1975 1800);
PAINT ORANGE (1975 1800);
DISPLAY INVISIBLE (1975 1800);
FORCEPROP 2 LAST $SEC 1
J 0
(1975 1800);
DISPLAY 0.914894 (1975 1800);
PAINT MONO (1975 1800);
DISPLAY INVISIBLE (1975 1800);
FORCEPROP 1 LAST PATH I12
J 0
(1975 1750);
DISPLAY 0.978723 (1975 1750);
PAINT WHITE (1975 1750);
DISPLAY INVISIBLE (1975 1750);
FORCEPROP 2 LAST ROOM SB_DECOUPLING
J 0
(1925 1600);
PAINT WHITE (1925 1600);
DISPLAY INVISIBLE (1925 1600);
FORCEADD GND..1
(1925 1300);
FORCEPROP 3 LASTPIN (1925 1350) SIG_NAME GND\g
J 0
(1935 1360);
DISPLAY 0.659574 (1935 1360);
PAINT MONO (1935 1360);
DISPLAY INVISIBLE (1935 1360);
FORCEPROP 1 LAST VOLTAGE 0
J 0
(1925 1300);
PAINT SKYBLUE (1925 1300);
DISPLAY INVISIBLE (1925 1300);
FORCEPROP 2 LAST BOM_COST SB
J 0
(1875 1375);
PAINT MONO (1875 1375);
DISPLAY INVISIBLE (1875 1375);
FORCEPROP 1 LAST SIZE 1B
J 0
(2000 1250);
DISPLAY 1.404255 (2000 1250);
PAINT GREEN (2000 1250);
DISPLAY INVISIBLE (2000 1250);
FORCEPROP 2 LAST CDS_LIB mstr_symbols
J 0
(1925 1300);
PAINT ORANGE (1925 1300);
DISPLAY INVISIBLE (1925 1300);
FORCEPROP 1 LAST BODY_TYPE PLUMBING
J 0
(1880 1257);
DISPLAY 0.340426 (1880 1257);
PAINT GREEN (1880 1257);
DISPLAY INVISIBLE (1880 1257);
FORCEPROP 1 LAST PATH I13
J 0
(2000 1300);
DISPLAY 0.872340 (2000 1300);
PAINT AQUA (2000 1300);
DISPLAY INVISIBLE (2000 1300);
FORCEPROP 2 LAST ROOM SB_DECOUPLING
J 0
(1450 1375);
PAINT WHITE (1450 1375);
DISPLAY INVISIBLE (1450 1375);
FORCEPROP 1 LAST HDL_POWER GND
J 0
(1925 1450);
DISPLAY 1.404255 (1925 1450);
PAINT GREEN (1925 1450);
DISPLAY INVISIBLE (1925 1450);
FORCEADD GND..1
(650 2350);
FORCEPROP 3 LASTPIN (650 2400) SIG_NAME GND\g
J 0
(660 2410);
DISPLAY 0.659574 (660 2410);
PAINT MONO (660 2410);
DISPLAY INVISIBLE (660 2410);
FORCEPROP 1 LAST VOLTAGE 0
J 0
(650 2350);
PAINT SKYBLUE (650 2350);
DISPLAY INVISIBLE (650 2350);
FORCEPROP 2 LAST BOM_COST SB
J 0
(600 2425);
PAINT MONO (600 2425);
DISPLAY INVISIBLE (600 2425);
FORCEPROP 2 LAST CDS_LIB mstr_symbols
J 0
(650 2350);
PAINT ORANGE (650 2350);
DISPLAY INVISIBLE (650 2350);
FORCEPROP 1 LAST SIZE 1B
J 0
(725 2300);
DISPLAY 1.404255 (725 2300);
PAINT GREEN (725 2300);
DISPLAY INVISIBLE (725 2300);
FORCEPROP 1 LAST BODY_TYPE PLUMBING
J 0
(605 2307);
DISPLAY 0.340426 (605 2307);
PAINT GREEN (605 2307);
DISPLAY INVISIBLE (605 2307);
FORCEPROP 1 LAST PATH I14
J 0
(725 2350);
DISPLAY 0.872340 (725 2350);
PAINT AQUA (725 2350);
DISPLAY INVISIBLE (725 2350);
FORCEPROP 2 LAST ROOM SB_DECOUPLING
J 0
(175 2425);
PAINT WHITE (175 2425);
DISPLAY INVISIBLE (175 2425);
FORCEPROP 1 LAST HDL_POWER GND
J 0
(650 2500);
DISPLAY 1.404255 (650 2500);
PAINT GREEN (650 2500);
DISPLAY INVISIBLE (650 2500);
FORCEADD CAP..1
(425 2650);
FORCEPROP 1 LAST LOCATION C2N21
J 0
(475 2750);
DISPLAY 0.617021 (475 2750);
PAINT AQUA (475 2750);
FORCEPROP 1 LAST PART_NUMBER E15431-002
J 0
(475 2500);
DISPLAY 0.617021 (475 2500);
PAINT BLUE (475 2500);
FORCEPROP 1 LAST VALUE 10UF
J 0
(475 2700);
DISPLAY 0.617021 (475 2700);
PAINT SKYBLUE (475 2700);
FORCEPROP 1 LAST TOLERANCE 20%
J 0
(475 2600);
DISPLAY 0.617021 (475 2600);
PAINT SKYBLUE (475 2600);
FORCEPROP 1 LAST PACK_TYPE 0603
J 0
(475 2450);
DISPLAY 0.617021 (475 2450);
PAINT SKYBLUE (475 2450);
FORCEPROP 1 LAST VOLTAGE 6.3V
J 0
(475 2650);
DISPLAY 0.617021 (475 2650);
PAINT SKYBLUE (475 2650);
FORCEPROP 1 LAST MATERIAL X6S
J 0
(475 2550);
DISPLAY 0.617021 (475 2550);
PAINT SKYBLUE (475 2550);
FORCEPROP 1 LASTPIN (425 2550) $PN 2
J 0
(435 2530);
DISPLAY 0.617021 (435 2530);
PAINT WHITE (435 2530);
FORCEPROP 1 LASTPIN (425 2750) $PN 1
J 0
(435 2730);
DISPLAY 0.617021 (435 2730);
PAINT WHITE (435 2730);
FORCEPROP 2 LAST CDS_LIB mstr_discrete
J 0
(425 2650);
PAINT ORANGE (425 2650);
DISPLAY INVISIBLE (425 2650);
FORCEPROP 2 LAST BOM_COST SB
J 0
(475 2400);
PAINT MONO (475 2400);
DISPLAY INVISIBLE (475 2400);
FORCEPROP 2 LAST CDS_SEC 1
J 0
(475 2850);
DISPLAY 1.361702 (475 2850);
PAINT ORANGE (475 2850);
DISPLAY INVISIBLE (475 2850);
FORCEPROP 2 LAST $SEC 1
J 0
(475 2850);
DISPLAY 0.914894 (475 2850);
PAINT MONO (475 2850);
DISPLAY INVISIBLE (475 2850);
FORCEPROP 2 LAST CDS_LOCATION C2N21
J 0
(475 2750);
DISPLAY 0.617021 (475 2750);
PAINT AQUA (475 2750);
DISPLAY INVISIBLE (475 2750);
FORCEPROP 1 LAST PATH I15
J 0
(475 2800);
DISPLAY 0.978723 (475 2800);
PAINT WHITE (475 2800);
DISPLAY INVISIBLE (475 2800);
FORCEPROP 2 LAST ROOM SB_DECOUPLING
J 0
(425 2650);
PAINT WHITE (425 2650);
DISPLAY INVISIBLE (425 2650);
FORCEADD CAP_A..1
R 2
(0 2025);
FORCEPROP 1 LAST LOCATION C3N29
J 2
(-50 2125);
DISPLAY 0.617021 (-50 2125);
PAINT AQUA (-50 2125);
FORCEPROP 1 LAST PART_NUMBER A36096-030
J 2
(-50 1875);
DISPLAY 0.617021 (-50 1875);
PAINT BLUE (-50 1875);
FORCEPROP 1 LAST VALUE 0.1UF
J 2
(-50 2075);
DISPLAY 0.617021 (-50 2075);
PAINT SKYBLUE (-50 2075);
FORCEPROP 1 LAST TOLERANCE 10%
J 2
(-50 1975);
DISPLAY 0.617021 (-50 1975);
PAINT SKYBLUE (-50 1975);
FORCEPROP 1 LAST PACK_TYPE 0402V
J 2
(-50 1825);
DISPLAY 0.617021 (-50 1825);
PAINT SKYBLUE (-50 1825);
FORCEPROP 1 LAST VOLTAGE 16V
J 2
(-50 2025);
DISPLAY 0.617021 (-50 2025);
PAINT SKYBLUE (-50 2025);
FORCEPROP 1 LAST MATERIAL X7R
J 2
(-50 1925);
DISPLAY 0.617021 (-50 1925);
PAINT SKYBLUE (-50 1925);
FORCEPROP 1 LASTPIN (0 2125) $PN 1
J 2
(-10 2105);
DISPLAY 0.617021 (-10 2105);
PAINT WHITE (-10 2105);
FORCEPROP 1 LASTPIN (0 1925) $PN 2
J 2
(-10 1905);
DISPLAY 0.617021 (-10 1905);
PAINT WHITE (-10 1905);
FORCEPROP 1 LAST PATH I16
J 2
(-50 2175);
DISPLAY 0.978723 (-50 2175);
PAINT WHITE (-50 2175);
DISPLAY INVISIBLE (-50 2175);
FORCEPROP 2 LAST ROOM SB_DECOUPLING
J 2
(0 2025);
PAINT WHITE (0 2025);
DISPLAY INVISIBLE (0 2025);
FORCEPROP 2 LAST CDS_LOCATION C3N29
J 2
(-50 2125);
DISPLAY 0.617021 (-50 2125);
PAINT AQUA (-50 2125);
DISPLAY INVISIBLE (-50 2125);
FORCEPROP 2 LAST BOM_COST SB
J 2
(-50 1775);
PAINT MONO (-50 1775);
DISPLAY INVISIBLE (-50 1775);
FORCEPROP 2 LAST CDS_LIB dev_discrete
J 0
(0 2025);
PAINT ORANGE (0 2025);
DISPLAY INVISIBLE (0 2025);
FORCEPROP 2 LAST CDS_SEC 1
J 2
(-50 2225);
DISPLAY 1.361702 (-50 2225);
PAINT ORANGE (-50 2225);
DISPLAY INVISIBLE (-50 2225);
FORCEPROP 2 LAST $SEC 1
J 2
(-50 2225);
DISPLAY 0.914894 (-50 2225);
PAINT MONO (-50 2225);
DISPLAY INVISIBLE (-50 2225);
FORCEADD GND..1
(0 1725);
FORCEPROP 3 LASTPIN (0 1775) SIG_NAME GND\g
J 0
(10 1785);
DISPLAY 0.659574 (10 1785);
PAINT MONO (10 1785);
DISPLAY INVISIBLE (10 1785);
FORCEPROP 1 LAST VOLTAGE 0
J 0
(0 1725);
PAINT SKYBLUE (0 1725);
DISPLAY INVISIBLE (0 1725);
FORCEPROP 2 LAST CDS_LIB mstr_symbols
J 0
(0 1725);
PAINT ORANGE (0 1725);
DISPLAY INVISIBLE (0 1725);
FORCEPROP 1 LAST SIZE 1B
J 0
(75 1675);
DISPLAY 1.404255 (75 1675);
PAINT GREEN (75 1675);
DISPLAY INVISIBLE (75 1675);
FORCEPROP 2 LAST BOM_COST SB
J 0
(-50 1800);
PAINT MONO (-50 1800);
DISPLAY INVISIBLE (-50 1800);
FORCEPROP 1 LAST BODY_TYPE PLUMBING
J 0
(-45 1682);
DISPLAY 0.340426 (-45 1682);
PAINT GREEN (-45 1682);
DISPLAY INVISIBLE (-45 1682);
FORCEPROP 1 LAST PATH I17
J 0
(75 1725);
DISPLAY 0.872340 (75 1725);
PAINT AQUA (75 1725);
DISPLAY INVISIBLE (75 1725);
FORCEPROP 2 LAST ROOM SB_DECOUPLING
J 0
(-475 1800);
PAINT WHITE (-475 1800);
DISPLAY INVISIBLE (-475 1800);
FORCEPROP 1 LAST HDL_POWER GND
J 0
(0 1875);
DISPLAY 1.404255 (0 1875);
PAINT GREEN (0 1875);
DISPLAY INVISIBLE (0 1875);
FORCEADD OFFPAGE..1
(-625 2275);
FORCEPROP 2 LAST $XR0 122 
J 0
(-877 2275);
DISPLAY 0.638298 (-877 2275);
PAINT MONO (-877 2275);
FORCEPROP 2 LAST CDS_LIB mstr_standard
J 0
(-625 2275);
PAINT ORANGE (-625 2275);
DISPLAY INVISIBLE (-625 2275);
FORCEPROP 1 LAST OFFPAGE TRUE
J 0
(-300 2150);
DISPLAY 1.170213 (-300 2150);
PAINT GREEN (-300 2150);
DISPLAY INVISIBLE (-300 2150);
FORCEPROP 1 LAST COMMENT_BODY TRUE
J 0
(-500 2175);
DISPLAY 1.170213 (-500 2175);
PAINT GREEN (-500 2175);
DISPLAY INVISIBLE (-500 2175);
FORCEPROP 2 LAST PATH I18
J 0
(-925 2325);
DISPLAY 1.021277 (-925 2325);
PAINT ORANGE (-925 2325);
DISPLAY INVISIBLE (-925 2325);
FORCEADD CAP..1
(-2550 4925);
FORCEPROP 1 LAST LOCATION C8C3
J 0
(-2500 5025);
DISPLAY 0.617021 (-2500 5025);
PAINT AQUA (-2500 5025);
FORCEPROP 1 LAST PART_NUMBER E15431-002
J 0
(-2500 4775);
DISPLAY 0.617021 (-2500 4775);
PAINT BLUE (-2500 4775);
FORCEPROP 1 LAST VALUE 10UF
J 0
(-2500 4975);
DISPLAY 0.617021 (-2500 4975);
PAINT SKYBLUE (-2500 4975);
FORCEPROP 1 LAST TOLERANCE 20%
J 0
(-2500 4875);
DISPLAY 0.617021 (-2500 4875);
PAINT SKYBLUE (-2500 4875);
FORCEPROP 1 LAST PACK_TYPE 0603
J 0
(-2500 4725);
DISPLAY 0.617021 (-2500 4725);
PAINT SKYBLUE (-2500 4725);
FORCEPROP 1 LAST VOLTAGE 6.3V
J 0
(-2500 4925);
DISPLAY 0.617021 (-2500 4925);
PAINT SKYBLUE (-2500 4925);
FORCEPROP 1 LAST MATERIAL X6S
J 0
(-2500 4825);
DISPLAY 0.617021 (-2500 4825);
PAINT SKYBLUE (-2500 4825);
FORCEPROP 2 LAST CDS_LIB mstr_discrete
J 0
(-2550 4925);
PAINT ORANGE (-2550 4925);
DISPLAY INVISIBLE (-2550 4925);
FORCEPROP 2 LAST BOM_COST SB
J 0
(-2500 4675);
PAINT MONO (-2500 4675);
DISPLAY INVISIBLE (-2500 4675);
FORCEPROP 2 LAST CDS_SEC 1
J 0
(-2500 5125);
DISPLAY 1.361702 (-2500 5125);
PAINT ORANGE (-2500 5125);
DISPLAY INVISIBLE (-2500 5125);
FORCEPROP 2 LAST $SEC 1
J 0
(-2500 5125);
DISPLAY 0.914894 (-2500 5125);
PAINT MONO (-2500 5125);
DISPLAY INVISIBLE (-2500 5125);
FORCEPROP 2 LAST CDS_LOCATION C8C3
J 0
(-2500 5025);
DISPLAY 0.617021 (-2500 5025);
PAINT AQUA (-2500 5025);
DISPLAY INVISIBLE (-2500 5025);
FORCEPROP 1 LAST PATH I19
J 0
(-2500 5075);
DISPLAY 0.978723 (-2500 5075);
PAINT WHITE (-2500 5075);
DISPLAY INVISIBLE (-2500 5075);
FORCEPROP 2 LAST ROOM SB_DECOUPLING
J 0
(-2550 4925);
PAINT WHITE (-2550 4925);
DISPLAY INVISIBLE (-2550 4925);
FORCEPROP 1 LASTPIN (-2550 4825) $PN 2
J 0
(-2540 4805);
DISPLAY 1.063830 (-2540 4805);
PAINT WHITE (-2540 4805);
DISPLAY INVISIBLE (-2540 4805);
FORCEPROP 1 LASTPIN (-2550 5025) $PN 1
J 0
(-2540 5005);
DISPLAY 1.063830 (-2540 5005);
PAINT WHITE (-2540 5005);
DISPLAY INVISIBLE (-2540 5005);
FORCEADD CAP..1
(1125 5003);
FORCEPROP 1 LAST LOCATION C7D2
J 0
(1175 5103);
DISPLAY 0.617021 (1175 5103);
PAINT AQUA (1175 5103);
FORCEPROP 1 LAST PART_NUMBER E15431-002
J 0
(1175 4853);
DISPLAY 0.617021 (1175 4853);
PAINT BLUE (1175 4853);
FORCEPROP 1 LAST VALUE 10UF
J 0
(1175 5053);
DISPLAY 0.617021 (1175 5053);
PAINT SKYBLUE (1175 5053);
FORCEPROP 1 LAST TOLERANCE 20%
J 0
(1175 4953);
DISPLAY 0.617021 (1175 4953);
PAINT SKYBLUE (1175 4953);
FORCEPROP 1 LAST PACK_TYPE 0603
J 0
(1175 4803);
DISPLAY 0.617021 (1175 4803);
PAINT SKYBLUE (1175 4803);
FORCEPROP 1 LAST VOLTAGE 6.3V
J 0
(1175 5003);
DISPLAY 0.617021 (1175 5003);
PAINT SKYBLUE (1175 5003);
FORCEPROP 1 LAST MATERIAL X6S
J 0
(1175 4903);
DISPLAY 0.617021 (1175 4903);
PAINT SKYBLUE (1175 4903);
FORCEPROP 1 LASTPIN (1125 4903) $PN 2
J 0
(1135 4883);
DISPLAY 0.617021 (1135 4883);
PAINT WHITE (1135 4883);
FORCEPROP 1 LASTPIN (1125 5103) $PN 1
J 0
(1135 5083);
DISPLAY 0.617021 (1135 5083);
PAINT WHITE (1135 5083);
FORCEPROP 2 LAST SEC_TYPE 0603
J 0
(1197 5212);
DISPLAY 1.361702 (1197 5212);
PAINT ORANGE (1197 5212);
DISPLAY INVISIBLE (1197 5212);
FORCEPROP 2 LAST BOM_COST SB
J 0
(1175 4753);
PAINT MONO (1175 4753);
DISPLAY INVISIBLE (1175 4753);
FORCEPROP 2 LAST CDS_LIB mstr_discrete
J 0
(1125 5003);
PAINT ORANGE (1125 5003);
DISPLAY INVISIBLE (1125 5003);
FORCEPROP 2 LAST SEC 1
J 0
(1197 5212);
DISPLAY 0.914894 (1197 5212);
PAINT MONO (1197 5212);
DISPLAY INVISIBLE (1197 5212);
FORCEPROP 2 LAST CDS_LOCATION C7D2
J 0
(1175 5103);
DISPLAY 0.617021 (1175 5103);
PAINT AQUA (1175 5103);
DISPLAY INVISIBLE (1175 5103);
FORCEPROP 1 LAST PATH I2
J 0
(1175 5153);
DISPLAY 0.978723 (1175 5153);
PAINT WHITE (1175 5153);
DISPLAY INVISIBLE (1175 5153);
FORCEPROP 2 LAST ROOM SB_DECOUPLING
J 0
(1125 5003);
PAINT WHITE (1125 5003);
DISPLAY INVISIBLE (1125 5003);
FORCEADD CAP..1
(-2975 4925);
FORCEPROP 1 LAST LOCATION C8C4
J 0
(-2925 5025);
DISPLAY 0.617021 (-2925 5025);
PAINT AQUA (-2925 5025);
FORCEPROP 1 LAST PART_NUMBER E15431-002
J 0
(-2925 4775);
DISPLAY 0.617021 (-2925 4775);
PAINT BLUE (-2925 4775);
FORCEPROP 1 LAST VALUE 10UF
J 0
(-2925 4975);
DISPLAY 0.617021 (-2925 4975);
PAINT SKYBLUE (-2925 4975);
FORCEPROP 1 LAST TOLERANCE 20%
J 0
(-2925 4875);
DISPLAY 0.617021 (-2925 4875);
PAINT SKYBLUE (-2925 4875);
FORCEPROP 1 LAST PACK_TYPE 0603
J 0
(-2925 4725);
DISPLAY 0.617021 (-2925 4725);
PAINT SKYBLUE (-2925 4725);
FORCEPROP 1 LAST VOLTAGE 6.3V
J 0
(-2925 4925);
DISPLAY 0.617021 (-2925 4925);
PAINT SKYBLUE (-2925 4925);
FORCEPROP 1 LAST MATERIAL X6S
J 0
(-2925 4825);
DISPLAY 0.617021 (-2925 4825);
PAINT SKYBLUE (-2925 4825);
FORCEPROP 2 LAST CDS_LIB mstr_discrete
J 0
(-2975 4925);
PAINT ORANGE (-2975 4925);
DISPLAY INVISIBLE (-2975 4925);
FORCEPROP 2 LAST BOM_COST SB
J 0
(-2925 4675);
PAINT MONO (-2925 4675);
DISPLAY INVISIBLE (-2925 4675);
FORCEPROP 2 LAST CDS_SEC 1
J 0
(-2925 5125);
DISPLAY 1.361702 (-2925 5125);
PAINT ORANGE (-2925 5125);
DISPLAY INVISIBLE (-2925 5125);
FORCEPROP 2 LAST $SEC 1
J 0
(-2925 5125);
DISPLAY 0.914894 (-2925 5125);
PAINT MONO (-2925 5125);
DISPLAY INVISIBLE (-2925 5125);
FORCEPROP 2 LAST CDS_LOCATION C8C4
J 0
(-2925 5025);
DISPLAY 0.617021 (-2925 5025);
PAINT AQUA (-2925 5025);
DISPLAY INVISIBLE (-2925 5025);
FORCEPROP 1 LAST PATH I20
J 0
(-2925 5075);
DISPLAY 0.978723 (-2925 5075);
PAINT WHITE (-2925 5075);
DISPLAY INVISIBLE (-2925 5075);
FORCEPROP 2 LAST ROOM SB_DECOUPLING
J 0
(-2975 4925);
PAINT WHITE (-2975 4925);
DISPLAY INVISIBLE (-2975 4925);
FORCEPROP 1 LASTPIN (-2975 4825) $PN 2
J 0
(-2965 4805);
DISPLAY 1.063830 (-2965 4805);
PAINT WHITE (-2965 4805);
DISPLAY INVISIBLE (-2965 4805);
FORCEPROP 1 LASTPIN (-2975 5025) $PN 1
J 0
(-2965 5005);
DISPLAY 1.063830 (-2965 5005);
PAINT WHITE (-2965 5005);
DISPLAY INVISIBLE (-2965 5005);
FORCEADD CAP..1
(-3375 4925);
FORCEPROP 1 LAST LOCATION C8C5
J 0
(-3325 5025);
DISPLAY 0.617021 (-3325 5025);
PAINT AQUA (-3325 5025);
FORCEPROP 1 LAST PART_NUMBER E15431-002
J 0
(-3325 4775);
DISPLAY 0.617021 (-3325 4775);
PAINT BLUE (-3325 4775);
FORCEPROP 1 LAST VALUE 10UF
J 0
(-3325 4975);
DISPLAY 0.617021 (-3325 4975);
PAINT SKYBLUE (-3325 4975);
FORCEPROP 1 LAST TOLERANCE 20%
J 0
(-3325 4875);
DISPLAY 0.617021 (-3325 4875);
PAINT SKYBLUE (-3325 4875);
FORCEPROP 1 LAST PACK_TYPE 0603
J 0
(-3325 4725);
DISPLAY 0.617021 (-3325 4725);
PAINT SKYBLUE (-3325 4725);
FORCEPROP 1 LAST VOLTAGE 6.3V
J 0
(-3325 4925);
DISPLAY 0.617021 (-3325 4925);
PAINT SKYBLUE (-3325 4925);
FORCEPROP 1 LAST MATERIAL X6S
J 0
(-3325 4825);
DISPLAY 0.617021 (-3325 4825);
PAINT SKYBLUE (-3325 4825);
FORCEPROP 2 LAST CDS_LIB mstr_discrete
J 0
(-3375 4925);
PAINT ORANGE (-3375 4925);
DISPLAY INVISIBLE (-3375 4925);
FORCEPROP 2 LAST BOM_COST SB
J 0
(-3325 4675);
PAINT MONO (-3325 4675);
DISPLAY INVISIBLE (-3325 4675);
FORCEPROP 2 LAST CDS_SEC 1
J 0
(-3325 5125);
DISPLAY 1.361702 (-3325 5125);
PAINT ORANGE (-3325 5125);
DISPLAY INVISIBLE (-3325 5125);
FORCEPROP 2 LAST $SEC 1
J 0
(-3325 5125);
DISPLAY 0.914894 (-3325 5125);
PAINT MONO (-3325 5125);
DISPLAY INVISIBLE (-3325 5125);
FORCEPROP 2 LAST CDS_LOCATION C8C5
J 0
(-3325 5025);
DISPLAY 0.617021 (-3325 5025);
PAINT AQUA (-3325 5025);
DISPLAY INVISIBLE (-3325 5025);
FORCEPROP 1 LAST PATH I21
J 0
(-3325 5075);
DISPLAY 0.978723 (-3325 5075);
PAINT WHITE (-3325 5075);
DISPLAY INVISIBLE (-3325 5075);
FORCEPROP 2 LAST ROOM SB_DECOUPLING
J 0
(-3375 4925);
PAINT WHITE (-3375 4925);
DISPLAY INVISIBLE (-3375 4925);
FORCEPROP 1 LASTPIN (-3375 4825) $PN 2
J 0
(-3365 4805);
DISPLAY 1.063830 (-3365 4805);
PAINT WHITE (-3365 4805);
DISPLAY INVISIBLE (-3365 4805);
FORCEPROP 1 LASTPIN (-3375 5025) $PN 1
J 0
(-3365 5005);
DISPLAY 1.063830 (-3365 5005);
PAINT WHITE (-3365 5005);
DISPLAY INVISIBLE (-3365 5005);
FORCEADD CAP..1
(-3775 4925);
FORCEPROP 1 LAST LOCATION C8C6
J 0
(-3725 5025);
DISPLAY 0.617021 (-3725 5025);
PAINT AQUA (-3725 5025);
FORCEPROP 1 LAST PART_NUMBER E15431-002
J 0
(-3725 4775);
DISPLAY 0.617021 (-3725 4775);
PAINT BLUE (-3725 4775);
FORCEPROP 1 LAST VALUE 10UF
J 0
(-3725 4975);
DISPLAY 0.617021 (-3725 4975);
PAINT SKYBLUE (-3725 4975);
FORCEPROP 1 LAST TOLERANCE 20%
J 0
(-3725 4875);
DISPLAY 0.617021 (-3725 4875);
PAINT SKYBLUE (-3725 4875);
FORCEPROP 1 LAST PACK_TYPE 0603
J 0
(-3725 4725);
DISPLAY 0.617021 (-3725 4725);
PAINT SKYBLUE (-3725 4725);
FORCEPROP 1 LAST MATERIAL X6S
J 0
(-3725 4825);
DISPLAY 0.617021 (-3725 4825);
PAINT SKYBLUE (-3725 4825);
FORCEPROP 1 LASTPIN (-3775 4825) $PN 2
J 0
(-3765 4805);
DISPLAY 0.617021 (-3765 4805);
PAINT WHITE (-3765 4805);
FORCEPROP 1 LASTPIN (-3775 5025) $PN 1
J 0
(-3765 5005);
DISPLAY 0.617021 (-3765 5005);
PAINT WHITE (-3765 5005);
FORCEPROP 1 LAST VOLTAGE 6.3V
J 0
(-3725 4925);
PAINT SKYBLUE (-3725 4925);
DISPLAY INVISIBLE (-3725 4925);
FORCEPROP 2 LAST CDS_LIB mstr_discrete
J 0
(-3775 4925);
PAINT ORANGE (-3775 4925);
DISPLAY INVISIBLE (-3775 4925);
FORCEPROP 2 LAST BOM_COST SB
J 0
(-3725 4675);
PAINT MONO (-3725 4675);
DISPLAY INVISIBLE (-3725 4675);
FORCEPROP 2 LAST CDS_SEC 1
J 0
(-3725 5125);
DISPLAY 1.361702 (-3725 5125);
PAINT ORANGE (-3725 5125);
DISPLAY INVISIBLE (-3725 5125);
FORCEPROP 2 LAST $SEC 1
J 0
(-3725 5125);
DISPLAY 0.914894 (-3725 5125);
PAINT MONO (-3725 5125);
DISPLAY INVISIBLE (-3725 5125);
FORCEPROP 2 LAST CDS_LOCATION C8C6
J 0
(-3725 5025);
DISPLAY 0.617021 (-3725 5025);
PAINT AQUA (-3725 5025);
DISPLAY INVISIBLE (-3725 5025);
FORCEPROP 1 LAST PATH I22
J 0
(-3725 5075);
DISPLAY 0.978723 (-3725 5075);
PAINT WHITE (-3725 5075);
DISPLAY INVISIBLE (-3725 5075);
FORCEPROP 2 LAST ROOM SB_DECOUPLING
J 0
(-3775 4925);
PAINT WHITE (-3775 4925);
DISPLAY INVISIBLE (-3775 4925);
FORCEADD CAP..1
(-4175 4925);
FORCEPROP 1 LAST LOCATION C2N23
J 0
(-4125 5025);
DISPLAY 0.617021 (-4125 5025);
PAINT AQUA (-4125 5025);
FORCEPROP 1 LAST PART_NUMBER E15431-002
J 0
(-4125 4775);
DISPLAY 0.617021 (-4125 4775);
PAINT BLUE (-4125 4775);
FORCEPROP 1 LAST VALUE 10UF
J 0
(-4125 4975);
DISPLAY 0.617021 (-4125 4975);
PAINT SKYBLUE (-4125 4975);
FORCEPROP 1 LAST TOLERANCE 20%
J 0
(-4125 4875);
DISPLAY 0.617021 (-4125 4875);
PAINT SKYBLUE (-4125 4875);
FORCEPROP 1 LAST PACK_TYPE 0603
J 0
(-4125 4725);
DISPLAY 0.617021 (-4125 4725);
PAINT SKYBLUE (-4125 4725);
FORCEPROP 1 LAST VOLTAGE 6.3V
J 0
(-4125 4925);
DISPLAY 0.617021 (-4125 4925);
PAINT SKYBLUE (-4125 4925);
FORCEPROP 1 LAST MATERIAL X6S
J 0
(-4125 4825);
DISPLAY 0.617021 (-4125 4825);
PAINT SKYBLUE (-4125 4825);
FORCEPROP 2 LAST CDS_LIB mstr_discrete
J 0
(-4175 4925);
PAINT ORANGE (-4175 4925);
DISPLAY INVISIBLE (-4175 4925);
FORCEPROP 2 LAST BOM_COST SB
J 0
(-4125 4675);
PAINT MONO (-4125 4675);
DISPLAY INVISIBLE (-4125 4675);
FORCEPROP 2 LAST CDS_SEC 1
J 0
(-4125 5125);
DISPLAY 1.361702 (-4125 5125);
PAINT ORANGE (-4125 5125);
DISPLAY INVISIBLE (-4125 5125);
FORCEPROP 2 LAST $SEC 1
J 0
(-4125 5125);
DISPLAY 0.914894 (-4125 5125);
PAINT MONO (-4125 5125);
DISPLAY INVISIBLE (-4125 5125);
FORCEPROP 2 LAST CDS_LOCATION C2N23
J 0
(-4125 5025);
DISPLAY 0.617021 (-4125 5025);
PAINT AQUA (-4125 5025);
DISPLAY INVISIBLE (-4125 5025);
FORCEPROP 1 LAST PATH I24
J 0
(-4125 5075);
DISPLAY 0.978723 (-4125 5075);
PAINT WHITE (-4125 5075);
DISPLAY INVISIBLE (-4125 5075);
FORCEPROP 2 LAST ROOM SB_DECOUPLING
J 0
(-4175 4925);
PAINT WHITE (-4175 4925);
DISPLAY INVISIBLE (-4175 4925);
FORCEPROP 1 LASTPIN (-4175 4825) $PN 2
J 0
(-4165 4805);
DISPLAY 1.063830 (-4165 4805);
PAINT WHITE (-4165 4805);
DISPLAY INVISIBLE (-4165 4805);
FORCEPROP 1 LASTPIN (-4175 5025) $PN 1
J 0
(-4165 5005);
DISPLAY 1.063830 (-4165 5005);
PAINT WHITE (-4165 5005);
DISPLAY INVISIBLE (-4165 5005);
FORCEADD CAP..1
(-4575 4925);
FORCEPROP 1 LAST LOCATION C2N14
J 0
(-4525 5025);
DISPLAY 0.617021 (-4525 5025);
PAINT AQUA (-4525 5025);
FORCEPROP 1 LAST PART_NUMBER E15431-002
J 0
(-4525 4775);
DISPLAY 0.617021 (-4525 4775);
PAINT BLUE (-4525 4775);
FORCEPROP 1 LAST VALUE 10UF
J 0
(-4525 4975);
DISPLAY 0.617021 (-4525 4975);
PAINT SKYBLUE (-4525 4975);
FORCEPROP 1 LAST TOLERANCE 20%
J 0
(-4525 4875);
DISPLAY 0.617021 (-4525 4875);
PAINT SKYBLUE (-4525 4875);
FORCEPROP 1 LAST PACK_TYPE 0603
J 0
(-4525 4725);
DISPLAY 0.617021 (-4525 4725);
PAINT SKYBLUE (-4525 4725);
FORCEPROP 1 LAST MATERIAL X6S
J 0
(-4525 4825);
DISPLAY 0.617021 (-4525 4825);
PAINT SKYBLUE (-4525 4825);
FORCEPROP 1 LASTPIN (-4575 4825) $PN 2
J 0
(-4565 4805);
DISPLAY 0.617021 (-4565 4805);
PAINT WHITE (-4565 4805);
FORCEPROP 1 LASTPIN (-4575 5025) $PN 1
J 0
(-4565 5005);
DISPLAY 0.617021 (-4565 5005);
PAINT WHITE (-4565 5005);
FORCEPROP 1 LAST VOLTAGE 6.3V
J 0
(-4525 4925);
PAINT SKYBLUE (-4525 4925);
DISPLAY INVISIBLE (-4525 4925);
FORCEPROP 2 LAST CDS_LIB mstr_discrete
J 0
(-4575 4925);
PAINT ORANGE (-4575 4925);
DISPLAY INVISIBLE (-4575 4925);
FORCEPROP 2 LAST BOM_COST SB
J 0
(-4525 4675);
PAINT MONO (-4525 4675);
DISPLAY INVISIBLE (-4525 4675);
FORCEPROP 2 LAST CDS_SEC 1
J 0
(-4525 5125);
DISPLAY 1.361702 (-4525 5125);
PAINT ORANGE (-4525 5125);
DISPLAY INVISIBLE (-4525 5125);
FORCEPROP 2 LAST $SEC 1
J 0
(-4525 5125);
DISPLAY 0.914894 (-4525 5125);
PAINT MONO (-4525 5125);
DISPLAY INVISIBLE (-4525 5125);
FORCEPROP 2 LAST CDS_LOCATION C2N14
J 0
(-4525 5025);
DISPLAY 0.617021 (-4525 5025);
PAINT AQUA (-4525 5025);
DISPLAY INVISIBLE (-4525 5025);
FORCEPROP 1 LAST PATH I25
J 0
(-4525 5075);
DISPLAY 0.978723 (-4525 5075);
PAINT WHITE (-4525 5075);
DISPLAY INVISIBLE (-4525 5075);
FORCEPROP 2 LAST ROOM SB_DECOUPLING
J 0
(-4575 4925);
PAINT WHITE (-4575 4925);
DISPLAY INVISIBLE (-4575 4925);
FORCEADD GND..1
(-1475 3625);
FORCEPROP 3 LASTPIN (-1475 3675) SIG_NAME GND\g
J 0
(-1465 3685);
DISPLAY 0.659574 (-1465 3685);
PAINT MONO (-1465 3685);
DISPLAY INVISIBLE (-1465 3685);
FORCEPROP 1 LAST VOLTAGE 0.0V
J 0
(-1520 3582);
DISPLAY 0.340426 (-1520 3582);
PAINT SKYBLUE (-1520 3582);
DISPLAY INVISIBLE (-1520 3582);
FORCEPROP 2 LAST CDS_LIB mstr_symbols
J 0
(-1475 3625);
PAINT MONO (-1475 3625);
DISPLAY INVISIBLE (-1475 3625);
FORCEPROP 1 LAST SIZE 1B
J 0
(-1400 3575);
DISPLAY 1.170213 (-1400 3575);
PAINT AQUA (-1400 3575);
DISPLAY INVISIBLE (-1400 3575);
FORCEPROP 2 LAST BOM_COST SB
J 0
(-1450 3700);
DISPLAY 1.361702 (-1450 3700);
PAINT ORANGE (-1450 3700);
DISPLAY INVISIBLE (-1450 3700);
FORCEPROP 1 LAST BODY_TYPE PLUMBING
J 0
(-1520 3582);
DISPLAY 0.340426 (-1520 3582);
PAINT GREEN (-1520 3582);
DISPLAY INVISIBLE (-1520 3582);
FORCEPROP 1 LAST PATH I27
J 0
(-1400 3625);
DISPLAY 0.872340 (-1400 3625);
PAINT AQUA (-1400 3625);
DISPLAY INVISIBLE (-1400 3625);
FORCEPROP 2 LAST ROOM SB_DECOUPLING
J 0
(-1450 3700);
DISPLAY 1.361702 (-1450 3700);
PAINT ORANGE (-1450 3700);
DISPLAY INVISIBLE (-1450 3700);
FORCEPROP 1 LAST HDL_POWER GND
J 0
(-1475 3775);
DISPLAY 1.170213 (-1475 3775);
PAINT GREEN (-1475 3775);
DISPLAY INVISIBLE (-1475 3775);
FORCEADD CAP..1
(-1475 3925);
FORCEPROP 1 LAST LOCATION C2N17
J 0
(-1425 4025);
DISPLAY 0.617021 (-1425 4025);
PAINT AQUA (-1425 4025);
FORCEPROP 1 LAST PART_NUMBER E15431-002
J 0
(-1425 3775);
DISPLAY 0.617021 (-1425 3775);
PAINT BLUE (-1425 3775);
FORCEPROP 1 LAST VALUE 10UF
J 0
(-1425 3975);
DISPLAY 0.617021 (-1425 3975);
PAINT SKYBLUE (-1425 3975);
FORCEPROP 1 LAST TOLERANCE 20%
J 0
(-1425 3875);
DISPLAY 0.617021 (-1425 3875);
PAINT SKYBLUE (-1425 3875);
FORCEPROP 1 LAST PACK_TYPE 0603
J 0
(-1425 3725);
DISPLAY 0.617021 (-1425 3725);
PAINT SKYBLUE (-1425 3725);
FORCEPROP 1 LAST VOLTAGE 6.3V
J 0
(-1425 3925);
DISPLAY 0.617021 (-1425 3925);
PAINT SKYBLUE (-1425 3925);
FORCEPROP 1 LAST MATERIAL X6S
J 0
(-1425 3825);
DISPLAY 0.617021 (-1425 3825);
PAINT SKYBLUE (-1425 3825);
FORCEPROP 1 LASTPIN (-1475 3825) $PN 2
J 0
(-1465 3805);
DISPLAY 0.617021 (-1465 3805);
PAINT WHITE (-1465 3805);
FORCEPROP 1 LASTPIN (-1475 4025) $PN 1
J 0
(-1465 4005);
DISPLAY 0.617021 (-1465 4005);
PAINT WHITE (-1465 4005);
FORCEPROP 2 LAST CDS_LIB mstr_discrete
J 0
(-1475 3925);
PAINT MONO (-1475 3925);
DISPLAY INVISIBLE (-1475 3925);
FORCEPROP 2 LAST BOM_COST SB
J 0
(-1425 4125);
DISPLAY 1.361702 (-1425 4125);
PAINT ORANGE (-1425 4125);
DISPLAY INVISIBLE (-1425 4125);
FORCEPROP 2 LAST CDS_SEC 1
J 0
(-1425 4125);
DISPLAY 1.361702 (-1425 4125);
PAINT ORANGE (-1425 4125);
DISPLAY INVISIBLE (-1425 4125);
FORCEPROP 2 LAST $SEC 1
J 0
(-1425 4125);
DISPLAY 0.914894 (-1425 4125);
PAINT MONO (-1425 4125);
DISPLAY INVISIBLE (-1425 4125);
FORCEPROP 2 LAST CDS_LOCATION C2N17
J 0
(-1425 4025);
DISPLAY 0.617021 (-1425 4025);
PAINT AQUA (-1425 4025);
DISPLAY INVISIBLE (-1425 4025);
FORCEPROP 1 LAST PATH I28
J 0
(-1425 4075);
DISPLAY 0.978723 (-1425 4075);
PAINT WHITE (-1425 4075);
DISPLAY INVISIBLE (-1425 4075);
FORCEPROP 2 LAST ROOM SB_DECOUPLING
J 0
(-1425 4075);
DISPLAY 1.361702 (-1425 4075);
PAINT ORANGE (-1425 4075);
DISPLAY INVISIBLE (-1425 4075);
FORCEADD CAP_A..1
(-3450 3925);
FORCEPROP 1 LAST LOCATION C2N18
J 0
(-3400 4025);
DISPLAY 0.617021 (-3400 4025);
PAINT AQUA (-3400 4025);
FORCEPROP 1 LAST PART_NUMBER D97712-004
J 0
(-3400 3775);
DISPLAY 0.617021 (-3400 3775);
PAINT BLUE (-3400 3775);
FORCEPROP 1 LAST VALUE 1.0UF
J 0
(-3400 3975);
DISPLAY 0.617021 (-3400 3975);
PAINT SKYBLUE (-3400 3975);
FORCEPROP 1 LAST TOLERANCE 10%
J 0
(-3400 3875);
DISPLAY 0.617021 (-3400 3875);
PAINT SKYBLUE (-3400 3875);
FORCEPROP 1 LAST PACK_TYPE 0402V
J 0
(-3400 3725);
DISPLAY 0.617021 (-3400 3725);
PAINT SKYBLUE (-3400 3725);
FORCEPROP 1 LAST VOLTAGE 6.3V
J 0
(-3400 3925);
DISPLAY 0.617021 (-3400 3925);
PAINT SKYBLUE (-3400 3925);
FORCEPROP 1 LAST MATERIAL X6S
J 0
(-3400 3825);
DISPLAY 0.617021 (-3400 3825);
PAINT SKYBLUE (-3400 3825);
FORCEPROP 1 LASTPIN (-3450 4025) $PN 1
J 0
(-3440 4005);
DISPLAY 0.617021 (-3440 4005);
PAINT WHITE (-3440 4005);
FORCEPROP 1 LASTPIN (-3450 3825) $PN 2
J 0
(-3440 3805);
DISPLAY 0.617021 (-3440 3805);
PAINT WHITE (-3440 3805);
FORCEPROP 2 LAST CDS_LOCATION C2N18
J 0
(-3400 4025);
DISPLAY 0.617021 (-3400 4025);
PAINT AQUA (-3400 4025);
DISPLAY INVISIBLE (-3400 4025);
FORCEPROP 2 LAST BOM_COST SB
J 0
(-3400 3675);
PAINT MONO (-3400 3675);
DISPLAY INVISIBLE (-3400 3675);
FORCEPROP 2 LAST CDS_LIB dev_discrete
J 0
(-3450 3925);
PAINT ORANGE (-3450 3925);
DISPLAY INVISIBLE (-3450 3925);
FORCEPROP 2 LAST CDS_SEC 1
J 0
(-3400 4125);
DISPLAY 1.361702 (-3400 4125);
PAINT ORANGE (-3400 4125);
DISPLAY INVISIBLE (-3400 4125);
FORCEPROP 2 LAST $SEC 1
J 0
(-3400 4125);
DISPLAY 0.914894 (-3400 4125);
PAINT MONO (-3400 4125);
DISPLAY INVISIBLE (-3400 4125);
FORCEPROP 1 LAST PATH I29
J 0
(-3400 4075);
DISPLAY 0.978723 (-3400 4075);
PAINT WHITE (-3400 4075);
DISPLAY INVISIBLE (-3400 4075);
FORCEPROP 2 LAST ROOM SB_DECOUPLING
J 0
(-3450 3925);
PAINT WHITE (-3450 3925);
DISPLAY INVISIBLE (-3450 3925);
FORCEADD GND..1
(1125 4725);
FORCEPROP 3 LASTPIN (1125 4775) SIG_NAME GND\g
J 0
(1135 4785);
DISPLAY 0.659574 (1135 4785);
PAINT MONO (1135 4785);
DISPLAY INVISIBLE (1135 4785);
FORCEPROP 1 LAST VOLTAGE 0
J 0
(1125 4725);
PAINT SKYBLUE (1125 4725);
DISPLAY INVISIBLE (1125 4725);
FORCEPROP 2 LAST BOM_COST SB
J 0
(1075 4800);
PAINT MONO (1075 4800);
DISPLAY INVISIBLE (1075 4800);
FORCEPROP 1 LAST SIZE 1B
J 0
(1200 4675);
DISPLAY 1.404255 (1200 4675);
PAINT GREEN (1200 4675);
DISPLAY INVISIBLE (1200 4675);
FORCEPROP 2 LAST CDS_LIB mstr_symbols
J 0
(1125 4725);
PAINT ORANGE (1125 4725);
DISPLAY INVISIBLE (1125 4725);
FORCEPROP 1 LAST BODY_TYPE PLUMBING
J 0
(1080 4682);
DISPLAY 0.340426 (1080 4682);
PAINT GREEN (1080 4682);
DISPLAY INVISIBLE (1080 4682);
FORCEPROP 1 LAST PATH I3
J 0
(1200 4725);
DISPLAY 0.872340 (1200 4725);
PAINT AQUA (1200 4725);
DISPLAY INVISIBLE (1200 4725);
FORCEPROP 2 LAST ROOM SB_DECOUPLING
J 0
(650 4800);
PAINT WHITE (650 4800);
DISPLAY INVISIBLE (650 4800);
FORCEPROP 1 LAST HDL_POWER GND
J 0
(1125 4875);
DISPLAY 1.404255 (1125 4875);
PAINT GREEN (1125 4875);
DISPLAY INVISIBLE (1125 4875);
FORCEADD CAP_A..1
(-3100 2750);
FORCEPROP 1 LAST LOCATION C8B2
J 0
(-3050 2850);
DISPLAY 0.617021 (-3050 2850);
PAINT AQUA (-3050 2850);
FORCEPROP 1 LAST PART_NUMBER E15431-004
J 0
(-3050 2600);
DISPLAY 0.617021 (-3050 2600);
PAINT BLUE (-3050 2600);
FORCEPROP 1 LAST VALUE 22.0UF
J 0
(-3050 2800);
DISPLAY 0.617021 (-3050 2800);
PAINT SKYBLUE (-3050 2800);
FORCEPROP 1 LAST TOLERANCE 20%
J 0
(-3050 2700);
DISPLAY 0.617021 (-3050 2700);
PAINT SKYBLUE (-3050 2700);
FORCEPROP 1 LAST PACK_TYPE 0603V
J 0
(-3050 2550);
DISPLAY 0.617021 (-3050 2550);
PAINT SKYBLUE (-3050 2550);
FORCEPROP 1 LAST VOLTAGE 4V
J 0
(-3050 2750);
DISPLAY 0.617021 (-3050 2750);
PAINT SKYBLUE (-3050 2750);
FORCEPROP 1 LAST MATERIAL X6S
J 0
(-3050 2650);
DISPLAY 0.617021 (-3050 2650);
PAINT SKYBLUE (-3050 2650);
FORCEPROP 2 LAST CDS_LOCATION C8B2
J 0
(-3050 2850);
DISPLAY 0.617021 (-3050 2850);
PAINT AQUA (-3050 2850);
DISPLAY INVISIBLE (-3050 2850);
FORCEPROP 2 LAST BOM_COST SB
J 0
(-3050 2500);
PAINT MONO (-3050 2500);
DISPLAY INVISIBLE (-3050 2500);
FORCEPROP 2 LAST CDS_LIB dev_discrete
J 0
(-3100 2750);
PAINT ORANGE (-3100 2750);
DISPLAY INVISIBLE (-3100 2750);
FORCEPROP 2 LAST CDS_SEC 1
J 0
(-3050 2950);
DISPLAY 1.361702 (-3050 2950);
PAINT ORANGE (-3050 2950);
DISPLAY INVISIBLE (-3050 2950);
FORCEPROP 2 LAST $SEC 1
J 0
(-3050 2950);
DISPLAY 0.914894 (-3050 2950);
PAINT MONO (-3050 2950);
DISPLAY INVISIBLE (-3050 2950);
FORCEPROP 1 LAST PATH I30
J 0
(-3050 2900);
DISPLAY 0.978723 (-3050 2900);
PAINT WHITE (-3050 2900);
DISPLAY INVISIBLE (-3050 2900);
FORCEPROP 2 LAST ROOM SB_DECOUPLING
J 0
(-3100 2750);
PAINT WHITE (-3100 2750);
DISPLAY INVISIBLE (-3100 2750);
FORCEPROP 1 LASTPIN (-3100 2850) $PN 1
J 0
(-3090 2830);
DISPLAY 1.063830 (-3090 2830);
PAINT WHITE (-3090 2830);
DISPLAY INVISIBLE (-3090 2830);
FORCEPROP 1 LASTPIN (-3100 2650) $PN 2
J 0
(-3090 2630);
DISPLAY 1.063830 (-3090 2630);
PAINT WHITE (-3090 2630);
DISPLAY INVISIBLE (-3090 2630);
FORCEADD P1V8_PCH_STBY..1
(-1975 2175);
FORCEPROP 3 LASTPIN (-1975 2125) SIG_NAME P1V8_PCH_STBY\g
J 0
(-1965 2135);
DISPLAY 0.659574 (-1965 2135);
PAINT MONO (-1965 2135);
DISPLAY INVISIBLE (-1965 2135);
FORCEPROP 1 LAST VOLTAGE 1.8V
J 0
(-2020 2132);
DISPLAY 0.340426 (-2020 2132);
PAINT SKYBLUE (-2020 2132);
DISPLAY INVISIBLE (-2020 2132);
FORCEPROP 2 LAST BOM_COST SB
J 0
(-1975 2325);
PAINT MONO (-1975 2325);
DISPLAY INVISIBLE (-1975 2325);
FORCEPROP 2 LAST CDS_LIB mstr_symbols
J 0
(-1975 2175);
PAINT ORANGE (-1975 2175);
DISPLAY INVISIBLE (-1975 2175);
FORCEPROP 1 LAST BODY_TYPE PLUMBING
J 0
(-2020 2132);
DISPLAY 0.340426 (-2020 2132);
PAINT GREEN (-2020 2132);
DISPLAY INVISIBLE (-2020 2132);
FORCEPROP 1 LAST PATH I31
J 0
(-1925 2200);
DISPLAY 0.872340 (-1925 2200);
PAINT AQUA (-1925 2200);
DISPLAY INVISIBLE (-1925 2200);
FORCEPROP 2 LAST ROOM SB_DECOUPLING
J 0
(-1975 2275);
DISPLAY 1.361702 (-1975 2275);
PAINT WHITE (-1975 2275);
DISPLAY INVISIBLE (-1975 2275);
FORCEPROP 1 LAST HDL_POWER P1V8_PCH_STBY
J 1
(-1975 2225);
DISPLAY 0.872340 (-1975 2225);
PAINT GREEN (-1975 2225);
DISPLAY INVISIBLE (-1975 2225);
FORCEADD CAP_A..1
(-1975 1900);
FORCEPROP 1 LAST LOCATION C8B3
J 0
(-1925 2000);
DISPLAY 0.617021 (-1925 2000);
PAINT AQUA (-1925 2000);
FORCEPROP 1 LAST PART_NUMBER E15431-004
J 0
(-1925 1750);
DISPLAY 0.617021 (-1925 1750);
PAINT BLUE (-1925 1750);
FORCEPROP 1 LAST VALUE 22.0UF
J 0
(-1925 1950);
DISPLAY 0.617021 (-1925 1950);
PAINT SKYBLUE (-1925 1950);
FORCEPROP 1 LAST TOLERANCE 20%
J 0
(-1925 1850);
DISPLAY 0.617021 (-1925 1850);
PAINT SKYBLUE (-1925 1850);
FORCEPROP 1 LAST PACK_TYPE 0603V
J 0
(-1925 1700);
DISPLAY 0.617021 (-1925 1700);
PAINT SKYBLUE (-1925 1700);
FORCEPROP 1 LAST VOLTAGE 4V
J 0
(-1925 1900);
DISPLAY 0.617021 (-1925 1900);
PAINT SKYBLUE (-1925 1900);
FORCEPROP 1 LAST MATERIAL X6S
J 0
(-1925 1800);
DISPLAY 0.617021 (-1925 1800);
PAINT SKYBLUE (-1925 1800);
FORCEPROP 1 LASTPIN (-1975 2000) $PN 1
J 0
(-1965 1980);
DISPLAY 0.617021 (-1965 1980);
PAINT WHITE (-1965 1980);
FORCEPROP 1 LASTPIN (-1975 1800) $PN 2
J 0
(-1965 1780);
DISPLAY 0.617021 (-1965 1780);
PAINT WHITE (-1965 1780);
FORCEPROP 2 LAST CDS_LOCATION C8B3
J 0
(-1925 2000);
DISPLAY 0.617021 (-1925 2000);
PAINT AQUA (-1925 2000);
DISPLAY INVISIBLE (-1925 2000);
FORCEPROP 2 LAST BOM_COST SB
J 0
(-1925 2100);
DISPLAY 1.361702 (-1925 2100);
PAINT ORANGE (-1925 2100);
DISPLAY INVISIBLE (-1925 2100);
FORCEPROP 2 LAST CDS_LIB dev_discrete
J 0
(-1975 1900);
PAINT ORANGE (-1975 1900);
DISPLAY INVISIBLE (-1975 1900);
FORCEPROP 2 LAST CDS_SEC 1
J 0
(-1925 2100);
DISPLAY 1.361702 (-1925 2100);
PAINT ORANGE (-1925 2100);
DISPLAY INVISIBLE (-1925 2100);
FORCEPROP 2 LAST $SEC 1
J 0
(-1925 2100);
DISPLAY 0.914894 (-1925 2100);
PAINT MONO (-1925 2100);
DISPLAY INVISIBLE (-1925 2100);
FORCEPROP 1 LAST PATH I32
J 0
(-1925 2050);
DISPLAY 0.978723 (-1925 2050);
PAINT WHITE (-1925 2050);
DISPLAY INVISIBLE (-1925 2050);
FORCEPROP 2 LAST ROOM SB_DECOUPLING
J 0
(-1925 2050);
DISPLAY 1.361702 (-1925 2050);
PAINT ORANGE (-1925 2050);
DISPLAY INVISIBLE (-1925 2050);
FORCEADD GND..1
(-1975 1575);
FORCEPROP 3 LASTPIN (-1975 1625) SIG_NAME GND\g
J 0
(-1965 1635);
DISPLAY 0.659574 (-1965 1635);
PAINT MONO (-1965 1635);
DISPLAY INVISIBLE (-1965 1635);
FORCEPROP 1 LAST VOLTAGE 0.0V
J 0
(-2020 1532);
DISPLAY 0.340426 (-2020 1532);
PAINT SKYBLUE (-2020 1532);
DISPLAY INVISIBLE (-2020 1532);
FORCEPROP 2 LAST CDS_LIB mstr_symbols
J 0
(-1975 1575);
PAINT MONO (-1975 1575);
DISPLAY INVISIBLE (-1975 1575);
FORCEPROP 1 LAST SIZE 1B
J 0
(-1900 1525);
DISPLAY 1.170213 (-1900 1525);
PAINT AQUA (-1900 1525);
DISPLAY INVISIBLE (-1900 1525);
FORCEPROP 2 LAST BOM_COST SB
J 0
(-1950 1650);
DISPLAY 1.361702 (-1950 1650);
PAINT ORANGE (-1950 1650);
DISPLAY INVISIBLE (-1950 1650);
FORCEPROP 1 LAST BODY_TYPE PLUMBING
J 0
(-2020 1532);
DISPLAY 0.340426 (-2020 1532);
PAINT GREEN (-2020 1532);
DISPLAY INVISIBLE (-2020 1532);
FORCEPROP 1 LAST PATH I33
J 0
(-1900 1575);
DISPLAY 0.872340 (-1900 1575);
PAINT AQUA (-1900 1575);
DISPLAY INVISIBLE (-1900 1575);
FORCEPROP 2 LAST ROOM SB_DECOUPLING
J 0
(-1950 1650);
DISPLAY 1.361702 (-1950 1650);
PAINT ORANGE (-1950 1650);
DISPLAY INVISIBLE (-1950 1650);
FORCEPROP 1 LAST HDL_POWER GND
J 0
(-1975 1725);
DISPLAY 1.170213 (-1975 1725);
PAINT GREEN (-1975 1725);
DISPLAY INVISIBLE (-1975 1725);
FORCEADD CAP_A..1
(-3825 3925);
FORCEPROP 1 LAST LOCATION C2N25
J 0
(-3775 4025);
DISPLAY 0.617021 (-3775 4025);
PAINT AQUA (-3775 4025);
FORCEPROP 1 LAST PART_NUMBER D97712-004
J 0
(-3775 3775);
DISPLAY 0.617021 (-3775 3775);
PAINT BLUE (-3775 3775);
FORCEPROP 1 LAST VALUE 1.0UF
J 0
(-3775 3975);
DISPLAY 0.617021 (-3775 3975);
PAINT SKYBLUE (-3775 3975);
FORCEPROP 1 LAST TOLERANCE 10%
J 0
(-3775 3875);
DISPLAY 0.617021 (-3775 3875);
PAINT SKYBLUE (-3775 3875);
FORCEPROP 1 LAST PACK_TYPE 0402V
J 0
(-3775 3725);
DISPLAY 0.617021 (-3775 3725);
PAINT SKYBLUE (-3775 3725);
FORCEPROP 1 LAST VOLTAGE 6.3V
J 0
(-3775 3925);
DISPLAY 0.617021 (-3775 3925);
PAINT SKYBLUE (-3775 3925);
FORCEPROP 1 LAST MATERIAL X6S
J 0
(-3775 3825);
DISPLAY 0.617021 (-3775 3825);
PAINT SKYBLUE (-3775 3825);
FORCEPROP 1 LASTPIN (-3825 4025) $PN 1
J 0
(-3815 4005);
DISPLAY 0.617021 (-3815 4005);
PAINT WHITE (-3815 4005);
FORCEPROP 1 LASTPIN (-3825 3825) $PN 2
J 0
(-3815 3805);
DISPLAY 0.617021 (-3815 3805);
PAINT WHITE (-3815 3805);
FORCEPROP 2 LAST CDS_LOCATION C2N25
J 0
(-3775 4025);
DISPLAY 0.617021 (-3775 4025);
PAINT AQUA (-3775 4025);
DISPLAY INVISIBLE (-3775 4025);
FORCEPROP 2 LAST BOM_COST SB
J 0
(-3775 3675);
PAINT MONO (-3775 3675);
DISPLAY INVISIBLE (-3775 3675);
FORCEPROP 2 LAST CDS_LIB dev_discrete
J 0
(-3825 3925);
PAINT ORANGE (-3825 3925);
DISPLAY INVISIBLE (-3825 3925);
FORCEPROP 2 LAST CDS_SEC 1
J 0
(-3775 4125);
DISPLAY 1.361702 (-3775 4125);
PAINT ORANGE (-3775 4125);
DISPLAY INVISIBLE (-3775 4125);
FORCEPROP 2 LAST $SEC 1
J 0
(-3775 4125);
DISPLAY 0.914894 (-3775 4125);
PAINT MONO (-3775 4125);
DISPLAY INVISIBLE (-3775 4125);
FORCEPROP 1 LAST PATH I34
J 0
(-3775 4075);
DISPLAY 0.978723 (-3775 4075);
PAINT WHITE (-3775 4075);
DISPLAY INVISIBLE (-3775 4075);
FORCEPROP 2 LAST ROOM SB_DECOUPLING
J 0
(-3825 3925);
PAINT WHITE (-3825 3925);
DISPLAY INVISIBLE (-3825 3925);
FORCEADD GND..1
(-4325 4575);
FORCEPROP 3 LASTPIN (-4325 4625) SIG_NAME GND\g
J 0
(-4315 4635);
DISPLAY 0.659574 (-4315 4635);
PAINT MONO (-4315 4635);
DISPLAY INVISIBLE (-4315 4635);
FORCEPROP 1 LAST VOLTAGE 0
J 0
(-4325 4575);
PAINT SKYBLUE (-4325 4575);
DISPLAY INVISIBLE (-4325 4575);
FORCEPROP 2 LAST BOM_COST SB
J 0
(-4375 4650);
PAINT MONO (-4375 4650);
DISPLAY INVISIBLE (-4375 4650);
FORCEPROP 2 LAST CDS_LIB mstr_symbols
J 0
(-4325 4575);
PAINT ORANGE (-4325 4575);
DISPLAY INVISIBLE (-4325 4575);
FORCEPROP 1 LAST SIZE 1B
J 0
(-4250 4525);
DISPLAY 1.404255 (-4250 4525);
PAINT GREEN (-4250 4525);
DISPLAY INVISIBLE (-4250 4525);
FORCEPROP 1 LAST BODY_TYPE PLUMBING
J 0
(-4370 4532);
DISPLAY 0.340426 (-4370 4532);
PAINT GREEN (-4370 4532);
DISPLAY INVISIBLE (-4370 4532);
FORCEPROP 1 LAST PATH I35
J 0
(-4250 4575);
DISPLAY 0.872340 (-4250 4575);
PAINT AQUA (-4250 4575);
DISPLAY INVISIBLE (-4250 4575);
FORCEPROP 2 LAST ROOM SB_DECOUPLING
J 0
(-4800 4650);
PAINT WHITE (-4800 4650);
DISPLAY INVISIBLE (-4800 4650);
FORCEPROP 1 LAST HDL_POWER GND
J 0
(-4325 4725);
DISPLAY 1.404255 (-4325 4725);
PAINT GREEN (-4325 4725);
DISPLAY INVISIBLE (-4325 4725);
FORCEADD CAP_A..1
(-4200 3925);
FORCEPROP 1 LAST LOCATION C2M16
J 0
(-4150 4025);
DISPLAY 0.617021 (-4150 4025);
PAINT AQUA (-4150 4025);
FORCEPROP 1 LAST PART_NUMBER D97712-004
J 0
(-4150 3775);
DISPLAY 0.617021 (-4150 3775);
PAINT BLUE (-4150 3775);
FORCEPROP 1 LAST VALUE 1.0UF
J 0
(-4150 3975);
DISPLAY 0.617021 (-4150 3975);
PAINT SKYBLUE (-4150 3975);
FORCEPROP 1 LAST TOLERANCE 10%
J 0
(-4150 3875);
DISPLAY 0.617021 (-4150 3875);
PAINT SKYBLUE (-4150 3875);
FORCEPROP 1 LAST PACK_TYPE 0402V
J 0
(-4150 3725);
DISPLAY 0.617021 (-4150 3725);
PAINT SKYBLUE (-4150 3725);
FORCEPROP 1 LAST VOLTAGE 6.3V
J 0
(-4150 3925);
DISPLAY 0.617021 (-4150 3925);
PAINT SKYBLUE (-4150 3925);
FORCEPROP 1 LAST MATERIAL X6S
J 0
(-4150 3825);
DISPLAY 0.617021 (-4150 3825);
PAINT SKYBLUE (-4150 3825);
FORCEPROP 1 LASTPIN (-4200 4025) $PN 1
J 0
(-4190 4005);
DISPLAY 0.617021 (-4190 4005);
PAINT WHITE (-4190 4005);
FORCEPROP 1 LASTPIN (-4200 3825) $PN 2
J 0
(-4190 3805);
DISPLAY 0.617021 (-4190 3805);
PAINT WHITE (-4190 3805);
FORCEPROP 2 LAST CDS_LOCATION C2M16
J 0
(-4150 4025);
DISPLAY 0.617021 (-4150 4025);
PAINT AQUA (-4150 4025);
DISPLAY INVISIBLE (-4150 4025);
FORCEPROP 2 LAST BOM_COST SB
J 0
(-4150 3675);
PAINT MONO (-4150 3675);
DISPLAY INVISIBLE (-4150 3675);
FORCEPROP 2 LAST CDS_LIB dev_discrete
J 0
(-4200 3925);
PAINT ORANGE (-4200 3925);
DISPLAY INVISIBLE (-4200 3925);
FORCEPROP 2 LAST CDS_SEC 1
J 0
(-4150 4125);
DISPLAY 1.361702 (-4150 4125);
PAINT ORANGE (-4150 4125);
DISPLAY INVISIBLE (-4150 4125);
FORCEPROP 2 LAST $SEC 1
J 0
(-4150 4125);
DISPLAY 0.914894 (-4150 4125);
PAINT MONO (-4150 4125);
DISPLAY INVISIBLE (-4150 4125);
FORCEPROP 1 LAST PATH I37
J 0
(-4150 4075);
DISPLAY 0.978723 (-4150 4075);
PAINT WHITE (-4150 4075);
DISPLAY INVISIBLE (-4150 4075);
FORCEPROP 2 LAST ROOM SB_DECOUPLING
J 0
(-4200 3925);
PAINT WHITE (-4200 3925);
DISPLAY INVISIBLE (-4200 3925);
FORCEADD CAP_A..1
(-3525 2750);
FORCEPROP 1 LAST LOCATION C7D3
J 0
(-3475 2850);
DISPLAY 0.617021 (-3475 2850);
PAINT AQUA (-3475 2850);
FORCEPROP 1 LAST PART_NUMBER E15431-004
J 0
(-3475 2600);
DISPLAY 0.617021 (-3475 2600);
PAINT BLUE (-3475 2600);
FORCEPROP 1 LAST VALUE 22.0UF
J 0
(-3475 2800);
DISPLAY 0.617021 (-3475 2800);
PAINT SKYBLUE (-3475 2800);
FORCEPROP 1 LAST TOLERANCE 20%
J 0
(-3475 2700);
DISPLAY 0.617021 (-3475 2700);
PAINT SKYBLUE (-3475 2700);
FORCEPROP 1 LAST PACK_TYPE 0603V
J 0
(-3475 2550);
DISPLAY 0.617021 (-3475 2550);
PAINT SKYBLUE (-3475 2550);
FORCEPROP 1 LAST VOLTAGE 4V
J 0
(-3475 2750);
DISPLAY 0.617021 (-3475 2750);
PAINT SKYBLUE (-3475 2750);
FORCEPROP 1 LAST MATERIAL X6S
J 0
(-3475 2650);
DISPLAY 0.617021 (-3475 2650);
PAINT SKYBLUE (-3475 2650);
FORCEPROP 2 LAST CDS_LOCATION C7D3
J 0
(-3475 2850);
DISPLAY 0.617021 (-3475 2850);
PAINT AQUA (-3475 2850);
DISPLAY INVISIBLE (-3475 2850);
FORCEPROP 2 LAST BOM_COST SB
J 0
(-3475 2500);
PAINT MONO (-3475 2500);
DISPLAY INVISIBLE (-3475 2500);
FORCEPROP 2 LAST CDS_LIB dev_discrete
J 0
(-3525 2750);
PAINT ORANGE (-3525 2750);
DISPLAY INVISIBLE (-3525 2750);
FORCEPROP 2 LAST CDS_SEC 1
J 0
(-3475 2950);
DISPLAY 1.361702 (-3475 2950);
PAINT ORANGE (-3475 2950);
DISPLAY INVISIBLE (-3475 2950);
FORCEPROP 2 LAST $SEC 1
J 0
(-3475 2950);
DISPLAY 0.914894 (-3475 2950);
PAINT MONO (-3475 2950);
DISPLAY INVISIBLE (-3475 2950);
FORCEPROP 1 LAST PATH I38
J 0
(-3475 2900);
DISPLAY 0.978723 (-3475 2900);
PAINT WHITE (-3475 2900);
DISPLAY INVISIBLE (-3475 2900);
FORCEPROP 2 LAST ROOM SB_DECOUPLING
J 0
(-3525 2750);
PAINT WHITE (-3525 2750);
DISPLAY INVISIBLE (-3525 2750);
FORCEPROP 1 LASTPIN (-3525 2850) $PN 1
J 0
(-3515 2830);
DISPLAY 1.063830 (-3515 2830);
PAINT WHITE (-3515 2830);
DISPLAY INVISIBLE (-3515 2830);
FORCEPROP 1 LASTPIN (-3525 2650) $PN 2
J 0
(-3515 2630);
DISPLAY 1.063830 (-3515 2630);
PAINT WHITE (-3515 2630);
DISPLAY INVISIBLE (-3515 2630);
FORCEADD CAP_A..1
(-3925 2750);
FORCEPROP 1 LAST LOCATION C8B4
J 0
(-3875 2850);
DISPLAY 0.617021 (-3875 2850);
PAINT AQUA (-3875 2850);
FORCEPROP 1 LAST PART_NUMBER E15431-004
J 0
(-3875 2600);
DISPLAY 0.617021 (-3875 2600);
PAINT BLUE (-3875 2600);
FORCEPROP 1 LAST VALUE 22.0UF
J 0
(-3875 2800);
DISPLAY 0.617021 (-3875 2800);
PAINT SKYBLUE (-3875 2800);
FORCEPROP 1 LAST TOLERANCE 20%
J 0
(-3875 2700);
DISPLAY 0.617021 (-3875 2700);
PAINT SKYBLUE (-3875 2700);
FORCEPROP 1 LAST PACK_TYPE 0603V
J 0
(-3875 2550);
DISPLAY 0.617021 (-3875 2550);
PAINT SKYBLUE (-3875 2550);
FORCEPROP 1 LAST VOLTAGE 4V
J 0
(-3875 2750);
DISPLAY 0.617021 (-3875 2750);
PAINT SKYBLUE (-3875 2750);
FORCEPROP 1 LAST MATERIAL X6S
J 0
(-3875 2650);
DISPLAY 0.617021 (-3875 2650);
PAINT SKYBLUE (-3875 2650);
FORCEPROP 2 LAST CDS_LOCATION C8B4
J 0
(-3875 2850);
DISPLAY 0.617021 (-3875 2850);
PAINT AQUA (-3875 2850);
DISPLAY INVISIBLE (-3875 2850);
FORCEPROP 2 LAST BOM_COST SB
J 0
(-3875 2500);
PAINT MONO (-3875 2500);
DISPLAY INVISIBLE (-3875 2500);
FORCEPROP 2 LAST CDS_LIB dev_discrete
J 0
(-3925 2750);
PAINT ORANGE (-3925 2750);
DISPLAY INVISIBLE (-3925 2750);
FORCEPROP 2 LAST CDS_SEC 1
J 0
(-3875 2950);
DISPLAY 1.361702 (-3875 2950);
PAINT ORANGE (-3875 2950);
DISPLAY INVISIBLE (-3875 2950);
FORCEPROP 2 LAST $SEC 1
J 0
(-3875 2950);
DISPLAY 0.914894 (-3875 2950);
PAINT MONO (-3875 2950);
DISPLAY INVISIBLE (-3875 2950);
FORCEPROP 1 LAST PATH I39
J 0
(-3875 2900);
DISPLAY 0.978723 (-3875 2900);
PAINT WHITE (-3875 2900);
DISPLAY INVISIBLE (-3875 2900);
FORCEPROP 2 LAST ROOM SB_DECOUPLING
J 0
(-3925 2750);
PAINT WHITE (-3925 2750);
DISPLAY INVISIBLE (-3925 2750);
FORCEPROP 1 LASTPIN (-3925 2850) $PN 1
J 0
(-3915 2830);
DISPLAY 1.063830 (-3915 2830);
PAINT WHITE (-3915 2830);
DISPLAY INVISIBLE (-3915 2830);
FORCEPROP 1 LASTPIN (-3925 2650) $PN 2
J 0
(-3915 2630);
DISPLAY 1.063830 (-3915 2630);
PAINT WHITE (-3915 2630);
DISPLAY INVISIBLE (-3915 2630);
FORCEADD CAP_A..1
(1725 2650);
FORCEPROP 1 LAST LOCATION C2N26
J 0
(1775 2750);
DISPLAY 0.617021 (1775 2750);
PAINT AQUA (1775 2750);
FORCEPROP 1 LAST PART_NUMBER D97712-004
J 0
(1775 2500);
DISPLAY 0.617021 (1775 2500);
PAINT BLUE (1775 2500);
FORCEPROP 1 LAST VALUE 1.0UF
J 0
(1775 2700);
DISPLAY 0.617021 (1775 2700);
PAINT SKYBLUE (1775 2700);
FORCEPROP 1 LAST TOLERANCE 10%
J 0
(1775 2600);
DISPLAY 0.617021 (1775 2600);
PAINT SKYBLUE (1775 2600);
FORCEPROP 1 LAST PACK_TYPE 0402V
J 0
(1775 2450);
DISPLAY 0.617021 (1775 2450);
PAINT SKYBLUE (1775 2450);
FORCEPROP 1 LAST VOLTAGE 6.3V
J 0
(1775 2650);
DISPLAY 0.617021 (1775 2650);
PAINT SKYBLUE (1775 2650);
FORCEPROP 1 LAST MATERIAL X6S
J 0
(1775 2550);
DISPLAY 0.617021 (1775 2550);
PAINT SKYBLUE (1775 2550);
FORCEPROP 1 LASTPIN (1725 2750) $PN 1
J 0
(1735 2730);
DISPLAY 0.617021 (1735 2730);
PAINT ORANGE (1735 2730);
FORCEPROP 1 LASTPIN (1725 2550) $PN 2
J 0
(1735 2530);
DISPLAY 0.617021 (1735 2530);
PAINT ORANGE (1735 2530);
FORCEPROP 2 LAST CDS_LOCATION C2N26
J 0
(1775 2750);
DISPLAY 0.617021 (1775 2750);
PAINT AQUA (1775 2750);
DISPLAY INVISIBLE (1775 2750);
FORCEPROP 2 LAST BOM_COST SB
J 0
(1775 2400);
PAINT MONO (1775 2400);
DISPLAY INVISIBLE (1775 2400);
FORCEPROP 2 LAST CDS_LIB dev_discrete
J 0
(1725 2650);
PAINT ORANGE (1725 2650);
DISPLAY INVISIBLE (1725 2650);
FORCEPROP 2 LAST CDS_SEC 1
J 0
(1775 2850);
DISPLAY 1.361702 (1775 2850);
PAINT ORANGE (1775 2850);
DISPLAY INVISIBLE (1775 2850);
FORCEPROP 2 LAST $SEC 1
J 0
(1775 2850);
DISPLAY 0.914894 (1775 2850);
PAINT MONO (1775 2850);
DISPLAY INVISIBLE (1775 2850);
FORCEPROP 1 LAST PATH I4
J 0
(1775 2800);
DISPLAY 0.978723 (1775 2800);
PAINT WHITE (1775 2800);
DISPLAY INVISIBLE (1775 2800);
FORCEPROP 2 LAST ROOM SB_DECOUPLING
J 0
(1725 2650);
PAINT WHITE (1725 2650);
DISPLAY INVISIBLE (1725 2650);
FORCEADD GND..1
(-4375 3575);
FORCEPROP 3 LASTPIN (-4375 3625) SIG_NAME GND\g
J 0
(-4365 3635);
DISPLAY 0.659574 (-4365 3635);
PAINT MONO (-4365 3635);
DISPLAY INVISIBLE (-4365 3635);
FORCEPROP 1 LAST VOLTAGE 0
J 0
(-4375 3575);
PAINT SKYBLUE (-4375 3575);
DISPLAY INVISIBLE (-4375 3575);
FORCEPROP 2 LAST BOM_COST SB
J 0
(-4425 3650);
PAINT MONO (-4425 3650);
DISPLAY INVISIBLE (-4425 3650);
FORCEPROP 1 LAST SIZE 1B
J 0
(-4300 3525);
DISPLAY 1.404255 (-4300 3525);
PAINT GREEN (-4300 3525);
DISPLAY INVISIBLE (-4300 3525);
FORCEPROP 2 LAST CDS_LIB mstr_symbols
J 0
(-4375 3575);
PAINT ORANGE (-4375 3575);
DISPLAY INVISIBLE (-4375 3575);
FORCEPROP 1 LAST BODY_TYPE PLUMBING
J 0
(-4420 3532);
DISPLAY 0.340426 (-4420 3532);
PAINT GREEN (-4420 3532);
DISPLAY INVISIBLE (-4420 3532);
FORCEPROP 1 LAST PATH I40
J 0
(-4300 3575);
DISPLAY 0.872340 (-4300 3575);
PAINT AQUA (-4300 3575);
DISPLAY INVISIBLE (-4300 3575);
FORCEPROP 2 LAST ROOM SB_DECOUPLING
J 0
(-4850 3650);
PAINT WHITE (-4850 3650);
DISPLAY INVISIBLE (-4850 3650);
FORCEPROP 1 LAST HDL_POWER GND
J 0
(-4375 3725);
DISPLAY 1.404255 (-4375 3725);
PAINT GREEN (-4375 3725);
DISPLAY INVISIBLE (-4375 3725);
FORCEADD CAP_A..1
(-4350 2750);
FORCEPROP 1 LAST LOCATION C8B1
J 0
(-4300 2850);
DISPLAY 0.617021 (-4300 2850);
PAINT AQUA (-4300 2850);
FORCEPROP 1 LAST PART_NUMBER E15431-004
J 0
(-4300 2600);
DISPLAY 0.617021 (-4300 2600);
PAINT BLUE (-4300 2600);
FORCEPROP 1 LAST VALUE 22.0UF
J 0
(-4300 2800);
DISPLAY 0.617021 (-4300 2800);
PAINT SKYBLUE (-4300 2800);
FORCEPROP 1 LAST TOLERANCE 20%
J 0
(-4300 2700);
DISPLAY 0.617021 (-4300 2700);
PAINT SKYBLUE (-4300 2700);
FORCEPROP 1 LAST PACK_TYPE 0603V
J 0
(-4300 2550);
DISPLAY 0.617021 (-4300 2550);
PAINT SKYBLUE (-4300 2550);
FORCEPROP 1 LAST VOLTAGE 4V
J 0
(-4300 2750);
DISPLAY 0.617021 (-4300 2750);
PAINT SKYBLUE (-4300 2750);
FORCEPROP 1 LAST MATERIAL X6S
J 0
(-4300 2650);
DISPLAY 0.617021 (-4300 2650);
PAINT SKYBLUE (-4300 2650);
FORCEPROP 2 LAST CDS_LOCATION C8B1
J 0
(-4300 2850);
DISPLAY 0.617021 (-4300 2850);
PAINT AQUA (-4300 2850);
DISPLAY INVISIBLE (-4300 2850);
FORCEPROP 2 LAST BOM_COST SB
J 0
(-4300 2500);
PAINT MONO (-4300 2500);
DISPLAY INVISIBLE (-4300 2500);
FORCEPROP 2 LAST CDS_LIB dev_discrete
J 0
(-4350 2750);
PAINT ORANGE (-4350 2750);
DISPLAY INVISIBLE (-4350 2750);
FORCEPROP 2 LAST CDS_SEC 1
J 0
(-4300 2950);
DISPLAY 1.361702 (-4300 2950);
PAINT ORANGE (-4300 2950);
DISPLAY INVISIBLE (-4300 2950);
FORCEPROP 2 LAST $SEC 1
J 0
(-4300 2950);
DISPLAY 0.914894 (-4300 2950);
PAINT MONO (-4300 2950);
DISPLAY INVISIBLE (-4300 2950);
FORCEPROP 1 LAST PATH I41
J 0
(-4300 2900);
DISPLAY 0.978723 (-4300 2900);
PAINT WHITE (-4300 2900);
DISPLAY INVISIBLE (-4300 2900);
FORCEPROP 2 LAST ROOM SB_DECOUPLING
J 0
(-4350 2750);
PAINT WHITE (-4350 2750);
DISPLAY INVISIBLE (-4350 2750);
FORCEPROP 1 LASTPIN (-4350 2850) $PN 1
J 0
(-4340 2830);
DISPLAY 1.063830 (-4340 2830);
PAINT WHITE (-4340 2830);
DISPLAY INVISIBLE (-4340 2830);
FORCEPROP 1 LASTPIN (-4350 2650) $PN 2
J 0
(-4340 2630);
DISPLAY 1.063830 (-4340 2630);
PAINT WHITE (-4340 2630);
DISPLAY INVISIBLE (-4340 2630);
FORCEADD CAP_A..1
(-4600 3925);
FORCEPROP 1 LAST LOCATION C3N23
J 0
(-4550 4025);
DISPLAY 0.617021 (-4550 4025);
PAINT AQUA (-4550 4025);
FORCEPROP 1 LAST PART_NUMBER D97712-004
J 0
(-4550 3775);
DISPLAY 0.617021 (-4550 3775);
PAINT BLUE (-4550 3775);
FORCEPROP 1 LAST VALUE 1.0UF
J 0
(-4550 3975);
DISPLAY 0.617021 (-4550 3975);
PAINT SKYBLUE (-4550 3975);
FORCEPROP 1 LAST TOLERANCE 10%
J 0
(-4550 3875);
DISPLAY 0.617021 (-4550 3875);
PAINT SKYBLUE (-4550 3875);
FORCEPROP 1 LAST PACK_TYPE 0402V
J 0
(-4550 3725);
DISPLAY 0.617021 (-4550 3725);
PAINT SKYBLUE (-4550 3725);
FORCEPROP 1 LAST VOLTAGE 6.3V
J 0
(-4550 3925);
DISPLAY 0.617021 (-4550 3925);
PAINT SKYBLUE (-4550 3925);
FORCEPROP 1 LAST MATERIAL X6S
J 0
(-4550 3825);
DISPLAY 0.617021 (-4550 3825);
PAINT SKYBLUE (-4550 3825);
FORCEPROP 1 LASTPIN (-4600 4025) $PN 1
J 0
(-4590 4005);
DISPLAY 0.617021 (-4590 4005);
PAINT WHITE (-4590 4005);
FORCEPROP 1 LASTPIN (-4600 3825) $PN 2
J 0
(-4590 3805);
DISPLAY 0.617021 (-4590 3805);
PAINT WHITE (-4590 3805);
FORCEPROP 2 LAST CDS_LOCATION C3N23
J 0
(-4550 4025);
DISPLAY 0.617021 (-4550 4025);
PAINT AQUA (-4550 4025);
DISPLAY INVISIBLE (-4550 4025);
FORCEPROP 2 LAST BOM_COST SB
J 0
(-4550 3675);
PAINT MONO (-4550 3675);
DISPLAY INVISIBLE (-4550 3675);
FORCEPROP 2 LAST CDS_LIB dev_discrete
J 0
(-4600 3925);
PAINT ORANGE (-4600 3925);
DISPLAY INVISIBLE (-4600 3925);
FORCEPROP 2 LAST CDS_SEC 1
J 0
(-4550 4125);
PAINT MONO (-4550 4125);
DISPLAY INVISIBLE (-4550 4125);
FORCEPROP 2 LAST $SEC 1
J 0
(-4550 4125);
PAINT MONO (-4550 4125);
DISPLAY INVISIBLE (-4550 4125);
FORCEPROP 1 LAST PATH I42
J 0
(-4550 4075);
DISPLAY 0.978723 (-4550 4075);
PAINT WHITE (-4550 4075);
DISPLAY INVISIBLE (-4550 4075);
FORCEPROP 2 LAST ROOM SB_DECOUPLING
J 0
(-4600 3925);
PAINT WHITE (-4600 3925);
DISPLAY INVISIBLE (-4600 3925);
FORCEADD CAP_A..1
(-4725 2750);
FORCEPROP 1 LAST LOCATION C2M1
J 0
(-4675 2850);
DISPLAY 0.617021 (-4675 2850);
PAINT AQUA (-4675 2850);
FORCEPROP 1 LAST PART_NUMBER E15431-004
J 0
(-4675 2600);
DISPLAY 0.617021 (-4675 2600);
PAINT BLUE (-4675 2600);
FORCEPROP 1 LAST VALUE 22.0UF
J 0
(-4675 2800);
DISPLAY 0.617021 (-4675 2800);
PAINT SKYBLUE (-4675 2800);
FORCEPROP 1 LAST TOLERANCE 20%
J 0
(-4675 2700);
DISPLAY 0.617021 (-4675 2700);
PAINT SKYBLUE (-4675 2700);
FORCEPROP 1 LAST PACK_TYPE 0603V
J 0
(-4675 2550);
DISPLAY 0.617021 (-4675 2550);
PAINT SKYBLUE (-4675 2550);
FORCEPROP 1 LAST VOLTAGE 4V
J 0
(-4675 2750);
DISPLAY 0.617021 (-4675 2750);
PAINT SKYBLUE (-4675 2750);
FORCEPROP 1 LAST MATERIAL X6S
J 0
(-4675 2650);
DISPLAY 0.617021 (-4675 2650);
PAINT SKYBLUE (-4675 2650);
FORCEPROP 2 LAST CDS_LOCATION C2M1
J 0
(-4675 2850);
DISPLAY 0.617021 (-4675 2850);
PAINT AQUA (-4675 2850);
DISPLAY INVISIBLE (-4675 2850);
FORCEPROP 2 LAST BOM_COST SB
J 0
(-4675 2500);
PAINT MONO (-4675 2500);
DISPLAY INVISIBLE (-4675 2500);
FORCEPROP 2 LAST CDS_LIB dev_discrete
J 0
(-4725 2750);
PAINT ORANGE (-4725 2750);
DISPLAY INVISIBLE (-4725 2750);
FORCEPROP 2 LAST CDS_SEC 1
J 0
(-4675 2950);
DISPLAY 1.361702 (-4675 2950);
PAINT ORANGE (-4675 2950);
DISPLAY INVISIBLE (-4675 2950);
FORCEPROP 2 LAST $SEC 1
J 0
(-4675 2950);
DISPLAY 0.914894 (-4675 2950);
PAINT MONO (-4675 2950);
DISPLAY INVISIBLE (-4675 2950);
FORCEPROP 1 LAST PATH I43
J 0
(-4675 2900);
DISPLAY 0.978723 (-4675 2900);
PAINT WHITE (-4675 2900);
DISPLAY INVISIBLE (-4675 2900);
FORCEPROP 2 LAST ROOM SB_DECOUPLING
J 0
(-4725 2750);
PAINT WHITE (-4725 2750);
DISPLAY INVISIBLE (-4725 2750);
FORCEPROP 1 LASTPIN (-4725 2850) $PN 1
J 0
(-4715 2830);
DISPLAY 1.063830 (-4715 2830);
PAINT WHITE (-4715 2830);
DISPLAY INVISIBLE (-4715 2830);
FORCEPROP 1 LASTPIN (-4725 2650) $PN 2
J 0
(-4715 2630);
DISPLAY 1.063830 (-4715 2630);
PAINT WHITE (-4715 2630);
DISPLAY INVISIBLE (-4715 2630);
FORCEADD P1V8_PCH_STBY..1
(-4850 3025);
FORCEPROP 3 LASTPIN (-4850 2975) SIG_NAME P1V8_PCH_STBY\g
J 0
(-4840 2985);
DISPLAY 0.659574 (-4840 2985);
PAINT MONO (-4840 2985);
DISPLAY INVISIBLE (-4840 2985);
FORCEPROP 1 LAST VOLTAGE 1.8V
J 0
(-4895 2982);
DISPLAY 0.340426 (-4895 2982);
PAINT SKYBLUE (-4895 2982);
DISPLAY INVISIBLE (-4895 2982);
FORCEPROP 2 LAST BOM_COST SB
J 0
(-4850 3175);
PAINT MONO (-4850 3175);
DISPLAY INVISIBLE (-4850 3175);
FORCEPROP 2 LAST CDS_LIB mstr_symbols
J 0
(-4850 3025);
PAINT ORANGE (-4850 3025);
DISPLAY INVISIBLE (-4850 3025);
FORCEPROP 1 LAST BODY_TYPE PLUMBING
J 0
(-4895 2982);
DISPLAY 0.340426 (-4895 2982);
PAINT GREEN (-4895 2982);
DISPLAY INVISIBLE (-4895 2982);
FORCEPROP 1 LAST PATH I44
J 0
(-4800 3050);
DISPLAY 0.872340 (-4800 3050);
PAINT AQUA (-4800 3050);
DISPLAY INVISIBLE (-4800 3050);
FORCEPROP 2 LAST ROOM SB_DECOUPLING
J 0
(-4850 3125);
DISPLAY 1.361702 (-4850 3125);
PAINT WHITE (-4850 3125);
DISPLAY INVISIBLE (-4850 3125);
FORCEPROP 1 LAST HDL_POWER P1V8_PCH_STBY
J 1
(-4850 3075);
DISPLAY 0.872340 (-4850 3075);
PAINT GREEN (-4850 3075);
DISPLAY INVISIBLE (-4850 3075);
FORCEADD CAP_A..1
(-5150 2750);
FORCEPROP 1 LAST LOCATION C2M2
J 0
(-5100 2850);
DISPLAY 0.617021 (-5100 2850);
PAINT AQUA (-5100 2850);
FORCEPROP 1 LAST PART_NUMBER E15431-004
J 0
(-5100 2600);
DISPLAY 0.617021 (-5100 2600);
PAINT BLUE (-5100 2600);
FORCEPROP 1 LAST VALUE 22.0UF
J 0
(-5100 2800);
DISPLAY 0.617021 (-5100 2800);
PAINT SKYBLUE (-5100 2800);
FORCEPROP 1 LAST TOLERANCE 20%
J 0
(-5100 2700);
DISPLAY 0.617021 (-5100 2700);
PAINT SKYBLUE (-5100 2700);
FORCEPROP 1 LAST PACK_TYPE 0603V
J 0
(-5100 2550);
DISPLAY 0.617021 (-5100 2550);
PAINT SKYBLUE (-5100 2550);
FORCEPROP 1 LAST VOLTAGE 4V
J 0
(-5100 2750);
DISPLAY 0.617021 (-5100 2750);
PAINT SKYBLUE (-5100 2750);
FORCEPROP 1 LAST MATERIAL X6S
J 0
(-5100 2650);
DISPLAY 0.617021 (-5100 2650);
PAINT SKYBLUE (-5100 2650);
FORCEPROP 2 LAST CDS_LOCATION C2M2
J 0
(-5100 2850);
DISPLAY 0.617021 (-5100 2850);
PAINT AQUA (-5100 2850);
DISPLAY INVISIBLE (-5100 2850);
FORCEPROP 2 LAST BOM_COST SB
J 0
(-5100 2500);
PAINT MONO (-5100 2500);
DISPLAY INVISIBLE (-5100 2500);
FORCEPROP 2 LAST CDS_LIB dev_discrete
J 0
(-5150 2750);
PAINT ORANGE (-5150 2750);
DISPLAY INVISIBLE (-5150 2750);
FORCEPROP 2 LAST CDS_SEC 1
J 0
(-5100 2950);
DISPLAY 1.361702 (-5100 2950);
PAINT ORANGE (-5100 2950);
DISPLAY INVISIBLE (-5100 2950);
FORCEPROP 2 LAST $SEC 1
J 0
(-5100 2950);
DISPLAY 0.914894 (-5100 2950);
PAINT MONO (-5100 2950);
DISPLAY INVISIBLE (-5100 2950);
FORCEPROP 1 LAST PATH I45
J 0
(-5100 2900);
DISPLAY 0.978723 (-5100 2900);
PAINT WHITE (-5100 2900);
DISPLAY INVISIBLE (-5100 2900);
FORCEPROP 2 LAST ROOM SB_DECOUPLING
J 0
(-5150 2750);
PAINT WHITE (-5150 2750);
DISPLAY INVISIBLE (-5150 2750);
FORCEPROP 1 LASTPIN (-5150 2850) $PN 1
J 0
(-5140 2830);
DISPLAY 1.063830 (-5140 2830);
PAINT WHITE (-5140 2830);
DISPLAY INVISIBLE (-5140 2830);
FORCEPROP 1 LASTPIN (-5150 2650) $PN 2
J 0
(-5140 2630);
DISPLAY 1.063830 (-5140 2630);
PAINT WHITE (-5140 2630);
DISPLAY INVISIBLE (-5140 2630);
FORCEADD GND..1
(-4075 2425);
FORCEPROP 3 LASTPIN (-4075 2475) SIG_NAME GND\g
J 0
(-4065 2485);
DISPLAY 0.659574 (-4065 2485);
PAINT MONO (-4065 2485);
DISPLAY INVISIBLE (-4065 2485);
FORCEPROP 1 LAST VOLTAGE 0
J 0
(-4075 2425);
PAINT SKYBLUE (-4075 2425);
DISPLAY INVISIBLE (-4075 2425);
FORCEPROP 1 LAST SIZE 1B
J 0
(-4000 2375);
DISPLAY 1.404255 (-4000 2375);
PAINT GREEN (-4000 2375);
DISPLAY INVISIBLE (-4000 2375);
FORCEPROP 2 LAST CDS_LIB mstr_symbols
J 0
(-4075 2425);
PAINT ORANGE (-4075 2425);
DISPLAY INVISIBLE (-4075 2425);
FORCEPROP 2 LAST BOM_COST SB
J 0
(-4125 2500);
PAINT MONO (-4125 2500);
DISPLAY INVISIBLE (-4125 2500);
FORCEPROP 1 LAST BODY_TYPE PLUMBING
J 0
(-4120 2382);
DISPLAY 0.340426 (-4120 2382);
PAINT GREEN (-4120 2382);
DISPLAY INVISIBLE (-4120 2382);
FORCEPROP 1 LAST PATH I46
J 0
(-4000 2425);
DISPLAY 0.872340 (-4000 2425);
PAINT AQUA (-4000 2425);
DISPLAY INVISIBLE (-4000 2425);
FORCEPROP 2 LAST ROOM SB_DECOUPLING
J 0
(-4550 2500);
PAINT WHITE (-4550 2500);
DISPLAY INVISIBLE (-4550 2500);
FORCEPROP 1 LAST HDL_POWER GND
J 0
(-4075 2575);
DISPLAY 1.404255 (-4075 2575);
PAINT GREEN (-4075 2575);
DISPLAY INVISIBLE (-4075 2575);
FORCEADD CAP_A..1
(-3600 1475);
FORCEPROP 1 LAST LOCATION C2N15
J 0
(-3550 1575);
DISPLAY 0.617021 (-3550 1575);
PAINT AQUA (-3550 1575);
FORCEPROP 1 LAST PART_NUMBER D97712-004
J 0
(-3550 1325);
DISPLAY 0.617021 (-3550 1325);
PAINT BLUE (-3550 1325);
FORCEPROP 1 LAST VALUE 1.0UF
J 0
(-3550 1525);
DISPLAY 0.617021 (-3550 1525);
PAINT SKYBLUE (-3550 1525);
FORCEPROP 1 LAST TOLERANCE 10%
J 0
(-3550 1425);
DISPLAY 0.617021 (-3550 1425);
PAINT SKYBLUE (-3550 1425);
FORCEPROP 1 LAST PACK_TYPE 0402V
J 0
(-3550 1275);
DISPLAY 0.617021 (-3550 1275);
PAINT SKYBLUE (-3550 1275);
FORCEPROP 1 LAST VOLTAGE 6.3V
J 0
(-3550 1475);
DISPLAY 0.617021 (-3550 1475);
PAINT SKYBLUE (-3550 1475);
FORCEPROP 1 LAST MATERIAL X6S
J 0
(-3550 1375);
DISPLAY 0.617021 (-3550 1375);
PAINT SKYBLUE (-3550 1375);
FORCEPROP 1 LASTPIN (-3600 1575) $PN 1
J 0
(-3590 1555);
DISPLAY 0.617021 (-3590 1555);
PAINT WHITE (-3590 1555);
FORCEPROP 1 LASTPIN (-3600 1375) $PN 2
J 0
(-3590 1355);
DISPLAY 0.617021 (-3590 1355);
PAINT WHITE (-3590 1355);
FORCEPROP 2 LAST CDS_LOCATION C2N15
J 0
(-3550 1575);
DISPLAY 0.617021 (-3550 1575);
PAINT AQUA (-3550 1575);
DISPLAY INVISIBLE (-3550 1575);
FORCEPROP 2 LAST BOM_COST SB
J 0
(-3550 1225);
PAINT MONO (-3550 1225);
DISPLAY INVISIBLE (-3550 1225);
FORCEPROP 2 LAST CDS_LIB dev_discrete
J 0
(-3600 1475);
PAINT ORANGE (-3600 1475);
DISPLAY INVISIBLE (-3600 1475);
FORCEPROP 2 LAST CDS_SEC 1
J 0
(-3550 1675);
DISPLAY 1.361702 (-3550 1675);
PAINT ORANGE (-3550 1675);
DISPLAY INVISIBLE (-3550 1675);
FORCEPROP 2 LAST $SEC 1
J 0
(-3550 1675);
DISPLAY 0.914894 (-3550 1675);
PAINT MONO (-3550 1675);
DISPLAY INVISIBLE (-3550 1675);
FORCEPROP 1 LAST PATH I47
J 0
(-3550 1625);
DISPLAY 0.978723 (-3550 1625);
PAINT WHITE (-3550 1625);
DISPLAY INVISIBLE (-3550 1625);
FORCEPROP 2 LAST ROOM SB_DECOUPLING
J 0
(-3600 1475);
PAINT WHITE (-3600 1475);
DISPLAY INVISIBLE (-3600 1475);
FORCEADD GND..1
(-3750 1150);
FORCEPROP 3 LASTPIN (-3750 1200) SIG_NAME GND\g
J 0
(-3740 1210);
DISPLAY 0.659574 (-3740 1210);
PAINT MONO (-3740 1210);
DISPLAY INVISIBLE (-3740 1210);
FORCEPROP 1 LAST VOLTAGE 0
J 0
(-3750 1150);
PAINT SKYBLUE (-3750 1150);
DISPLAY INVISIBLE (-3750 1150);
FORCEPROP 2 LAST BOM_COST SB
J 0
(-3800 1225);
PAINT MONO (-3800 1225);
DISPLAY INVISIBLE (-3800 1225);
FORCEPROP 2 LAST CDS_LIB mstr_symbols
J 0
(-3750 1150);
PAINT ORANGE (-3750 1150);
DISPLAY INVISIBLE (-3750 1150);
FORCEPROP 1 LAST SIZE 1B
J 0
(-3675 1100);
DISPLAY 1.404255 (-3675 1100);
PAINT GREEN (-3675 1100);
DISPLAY INVISIBLE (-3675 1100);
FORCEPROP 1 LAST BODY_TYPE PLUMBING
J 0
(-3795 1107);
DISPLAY 0.340426 (-3795 1107);
PAINT GREEN (-3795 1107);
DISPLAY INVISIBLE (-3795 1107);
FORCEPROP 1 LAST PATH I48
J 0
(-3675 1150);
DISPLAY 0.872340 (-3675 1150);
PAINT AQUA (-3675 1150);
DISPLAY INVISIBLE (-3675 1150);
FORCEPROP 2 LAST ROOM SB_DECOUPLING
J 0
(-4225 1225);
PAINT WHITE (-4225 1225);
DISPLAY INVISIBLE (-4225 1225);
FORCEPROP 1 LAST HDL_POWER GND
J 0
(-3750 1300);
DISPLAY 1.404255 (-3750 1300);
PAINT GREEN (-3750 1300);
DISPLAY INVISIBLE (-3750 1300);
FORCEADD CAP_A..1
(-3975 1475);
FORCEPROP 1 LAST LOCATION C3N21
J 0
(-3925 1575);
DISPLAY 0.617021 (-3925 1575);
PAINT AQUA (-3925 1575);
FORCEPROP 1 LAST PART_NUMBER D97712-004
J 0
(-3925 1325);
DISPLAY 0.617021 (-3925 1325);
PAINT BLUE (-3925 1325);
FORCEPROP 1 LAST VALUE 1.0UF
J 0
(-3925 1525);
DISPLAY 0.617021 (-3925 1525);
PAINT SKYBLUE (-3925 1525);
FORCEPROP 1 LAST TOLERANCE 10%
J 0
(-3925 1425);
DISPLAY 0.617021 (-3925 1425);
PAINT SKYBLUE (-3925 1425);
FORCEPROP 1 LAST PACK_TYPE 0402V
J 0
(-3925 1275);
DISPLAY 0.617021 (-3925 1275);
PAINT SKYBLUE (-3925 1275);
FORCEPROP 1 LAST VOLTAGE 6.3V
J 0
(-3925 1475);
DISPLAY 0.617021 (-3925 1475);
PAINT SKYBLUE (-3925 1475);
FORCEPROP 1 LAST MATERIAL X6S
J 0
(-3925 1375);
DISPLAY 0.617021 (-3925 1375);
PAINT SKYBLUE (-3925 1375);
FORCEPROP 1 LASTPIN (-3975 1575) $PN 1
J 0
(-3965 1555);
DISPLAY 0.617021 (-3965 1555);
PAINT WHITE (-3965 1555);
FORCEPROP 1 LASTPIN (-3975 1375) $PN 2
J 0
(-3965 1355);
DISPLAY 0.617021 (-3965 1355);
PAINT WHITE (-3965 1355);
FORCEPROP 2 LAST CDS_LOCATION C3N21
J 0
(-3925 1575);
DISPLAY 0.617021 (-3925 1575);
PAINT AQUA (-3925 1575);
DISPLAY INVISIBLE (-3925 1575);
FORCEPROP 2 LAST BOM_COST SB
J 0
(-3925 1225);
PAINT MONO (-3925 1225);
DISPLAY INVISIBLE (-3925 1225);
FORCEPROP 2 LAST CDS_LIB dev_discrete
J 0
(-3975 1475);
PAINT ORANGE (-3975 1475);
DISPLAY INVISIBLE (-3975 1475);
FORCEPROP 2 LAST CDS_SEC 1
J 0
(-3925 1675);
DISPLAY 1.361702 (-3925 1675);
PAINT ORANGE (-3925 1675);
DISPLAY INVISIBLE (-3925 1675);
FORCEPROP 2 LAST $SEC 1
J 0
(-3925 1675);
DISPLAY 0.914894 (-3925 1675);
PAINT MONO (-3925 1675);
DISPLAY INVISIBLE (-3925 1675);
FORCEPROP 1 LAST PATH I49
J 0
(-3925 1625);
DISPLAY 0.978723 (-3925 1625);
PAINT WHITE (-3925 1625);
DISPLAY INVISIBLE (-3925 1625);
FORCEPROP 2 LAST ROOM SB_DECOUPLING
J 0
(-3975 1475);
PAINT WHITE (-3975 1475);
DISPLAY INVISIBLE (-3975 1475);
FORCEADD CAP_A..1
(-4350 1475);
FORCEPROP 1 LAST LOCATION C3N25
J 0
(-4300 1575);
DISPLAY 0.617021 (-4300 1575);
PAINT AQUA (-4300 1575);
FORCEPROP 1 LAST PART_NUMBER D97712-004
J 0
(-4300 1325);
DISPLAY 0.617021 (-4300 1325);
PAINT BLUE (-4300 1325);
FORCEPROP 1 LAST VALUE 1.0UF
J 0
(-4300 1525);
DISPLAY 0.617021 (-4300 1525);
PAINT SKYBLUE (-4300 1525);
FORCEPROP 1 LAST TOLERANCE 10%
J 0
(-4300 1425);
DISPLAY 0.617021 (-4300 1425);
PAINT SKYBLUE (-4300 1425);
FORCEPROP 1 LAST PACK_TYPE 0402V
J 0
(-4300 1275);
DISPLAY 0.617021 (-4300 1275);
PAINT SKYBLUE (-4300 1275);
FORCEPROP 1 LAST VOLTAGE 6.3V
J 0
(-4300 1475);
DISPLAY 0.617021 (-4300 1475);
PAINT SKYBLUE (-4300 1475);
FORCEPROP 1 LAST MATERIAL X6S
J 0
(-4300 1375);
DISPLAY 0.617021 (-4300 1375);
PAINT SKYBLUE (-4300 1375);
FORCEPROP 1 LASTPIN (-4350 1575) $PN 1
J 0
(-4340 1555);
DISPLAY 0.617021 (-4340 1555);
PAINT WHITE (-4340 1555);
FORCEPROP 1 LASTPIN (-4350 1375) $PN 2
J 0
(-4340 1355);
DISPLAY 0.617021 (-4340 1355);
PAINT WHITE (-4340 1355);
FORCEPROP 2 LAST CDS_LOCATION C3N25
J 0
(-4300 1575);
DISPLAY 0.617021 (-4300 1575);
PAINT AQUA (-4300 1575);
DISPLAY INVISIBLE (-4300 1575);
FORCEPROP 2 LAST BOM_COST SB
J 0
(-4300 1225);
PAINT MONO (-4300 1225);
DISPLAY INVISIBLE (-4300 1225);
FORCEPROP 2 LAST CDS_LIB dev_discrete
J 0
(-4350 1475);
PAINT ORANGE (-4350 1475);
DISPLAY INVISIBLE (-4350 1475);
FORCEPROP 2 LAST CDS_SEC 1
J 0
(-4300 1675);
PAINT MONO (-4300 1675);
DISPLAY INVISIBLE (-4300 1675);
FORCEPROP 2 LAST $SEC 1
J 0
(-4300 1675);
PAINT MONO (-4300 1675);
DISPLAY INVISIBLE (-4300 1675);
FORCEPROP 1 LAST PATH I50
J 0
(-4300 1625);
DISPLAY 0.978723 (-4300 1625);
PAINT WHITE (-4300 1625);
DISPLAY INVISIBLE (-4300 1625);
FORCEPROP 2 LAST ROOM SB_DECOUPLING
J 0
(-4350 1475);
PAINT WHITE (-4350 1475);
DISPLAY INVISIBLE (-4350 1475);
FORCEADD P1V8_PCH_STBY..1
(-4950 1750);
FORCEPROP 3 LASTPIN (-4950 1700) SIG_NAME P1V8_PCH_STBY\g
J 0
(-4940 1710);
DISPLAY 0.659574 (-4940 1710);
PAINT MONO (-4940 1710);
DISPLAY INVISIBLE (-4940 1710);
FORCEPROP 1 LAST VOLTAGE 1.8V
J 0
(-4995 1707);
DISPLAY 0.340426 (-4995 1707);
PAINT SKYBLUE (-4995 1707);
DISPLAY INVISIBLE (-4995 1707);
FORCEPROP 2 LAST BOM_COST SB
J 0
(-4950 1900);
PAINT MONO (-4950 1900);
DISPLAY INVISIBLE (-4950 1900);
FORCEPROP 2 LAST CDS_LIB mstr_symbols
J 0
(-4950 1750);
PAINT ORANGE (-4950 1750);
DISPLAY INVISIBLE (-4950 1750);
FORCEPROP 1 LAST BODY_TYPE PLUMBING
J 0
(-4995 1707);
DISPLAY 0.340426 (-4995 1707);
PAINT GREEN (-4995 1707);
DISPLAY INVISIBLE (-4995 1707);
FORCEPROP 1 LAST PATH I51
J 0
(-4900 1775);
DISPLAY 0.872340 (-4900 1775);
PAINT AQUA (-4900 1775);
DISPLAY INVISIBLE (-4900 1775);
FORCEPROP 2 LAST ROOM SB_DECOUPLING
J 0
(-4950 1850);
DISPLAY 1.361702 (-4950 1850);
PAINT WHITE (-4950 1850);
DISPLAY INVISIBLE (-4950 1850);
FORCEPROP 1 LAST HDL_POWER P1V8_PCH_STBY
J 1
(-4950 1800);
DISPLAY 0.872340 (-4950 1800);
PAINT GREEN (-4950 1800);
DISPLAY INVISIBLE (-4950 1800);
FORCEADD CAP_A..1
(-4775 1475);
FORCEPROP 1 LAST LOCATION C2N16
J 0
(-4725 1575);
DISPLAY 0.617021 (-4725 1575);
PAINT AQUA (-4725 1575);
FORCEPROP 1 LAST PART_NUMBER D97712-004
J 0
(-4725 1325);
DISPLAY 0.617021 (-4725 1325);
PAINT BLUE (-4725 1325);
FORCEPROP 1 LAST VALUE 1.0UF
J 0
(-4725 1525);
DISPLAY 0.617021 (-4725 1525);
PAINT SKYBLUE (-4725 1525);
FORCEPROP 1 LAST TOLERANCE 10%
J 0
(-4725 1425);
DISPLAY 0.617021 (-4725 1425);
PAINT SKYBLUE (-4725 1425);
FORCEPROP 1 LAST PACK_TYPE 0402V
J 0
(-4725 1275);
DISPLAY 0.617021 (-4725 1275);
PAINT SKYBLUE (-4725 1275);
FORCEPROP 1 LAST VOLTAGE 6.3V
J 0
(-4725 1475);
DISPLAY 0.617021 (-4725 1475);
PAINT SKYBLUE (-4725 1475);
FORCEPROP 1 LAST MATERIAL X6S
J 0
(-4725 1375);
DISPLAY 0.617021 (-4725 1375);
PAINT SKYBLUE (-4725 1375);
FORCEPROP 1 LASTPIN (-4775 1575) $PN 1
J 0
(-4765 1555);
DISPLAY 0.617021 (-4765 1555);
PAINT WHITE (-4765 1555);
FORCEPROP 1 LASTPIN (-4775 1375) $PN 2
J 0
(-4765 1355);
DISPLAY 0.617021 (-4765 1355);
PAINT WHITE (-4765 1355);
FORCEPROP 2 LAST CDS_LOCATION C2N16
J 0
(-4725 1575);
DISPLAY 0.617021 (-4725 1575);
PAINT AQUA (-4725 1575);
DISPLAY INVISIBLE (-4725 1575);
FORCEPROP 2 LAST BOM_COST SB
J 0
(-4725 1225);
PAINT MONO (-4725 1225);
DISPLAY INVISIBLE (-4725 1225);
FORCEPROP 2 LAST CDS_LIB dev_discrete
J 0
(-4775 1475);
PAINT ORANGE (-4775 1475);
DISPLAY INVISIBLE (-4775 1475);
FORCEPROP 2 LAST CDS_SEC 1
J 0
(-4725 1675);
PAINT MONO (-4725 1675);
DISPLAY INVISIBLE (-4725 1675);
FORCEPROP 2 LAST $SEC 1
J 0
(-4725 1675);
PAINT MONO (-4725 1675);
DISPLAY INVISIBLE (-4725 1675);
FORCEPROP 1 LAST PATH I52
J 0
(-4725 1625);
DISPLAY 0.978723 (-4725 1625);
PAINT WHITE (-4725 1625);
DISPLAY INVISIBLE (-4725 1625);
FORCEPROP 2 LAST ROOM SB_DECOUPLING
J 0
(-4775 1475);
PAINT WHITE (-4775 1475);
DISPLAY INVISIBLE (-4775 1475);
FORCEADD CAP_A..1
(-5200 1475);
FORCEPROP 1 LAST LOCATION C3N22
J 0
(-5150 1575);
DISPLAY 0.617021 (-5150 1575);
PAINT AQUA (-5150 1575);
FORCEPROP 1 LAST PART_NUMBER D97712-004
J 0
(-5150 1325);
DISPLAY 0.617021 (-5150 1325);
PAINT BLUE (-5150 1325);
FORCEPROP 1 LAST VALUE 1.0UF
J 0
(-5150 1525);
DISPLAY 0.617021 (-5150 1525);
PAINT SKYBLUE (-5150 1525);
FORCEPROP 1 LAST TOLERANCE 10%
J 0
(-5150 1425);
DISPLAY 0.617021 (-5150 1425);
PAINT SKYBLUE (-5150 1425);
FORCEPROP 1 LAST PACK_TYPE 0402V
J 0
(-5150 1275);
DISPLAY 0.617021 (-5150 1275);
PAINT SKYBLUE (-5150 1275);
FORCEPROP 1 LAST VOLTAGE 6.3V
J 0
(-5150 1475);
DISPLAY 0.617021 (-5150 1475);
PAINT SKYBLUE (-5150 1475);
FORCEPROP 1 LAST MATERIAL X6S
J 0
(-5150 1375);
DISPLAY 0.617021 (-5150 1375);
PAINT SKYBLUE (-5150 1375);
FORCEPROP 1 LASTPIN (-5200 1575) $PN 1
J 0
(-5190 1555);
DISPLAY 0.617021 (-5190 1555);
PAINT WHITE (-5190 1555);
FORCEPROP 1 LASTPIN (-5200 1375) $PN 2
J 0
(-5190 1355);
DISPLAY 0.617021 (-5190 1355);
PAINT WHITE (-5190 1355);
FORCEPROP 2 LAST CDS_LOCATION C3N22
J 0
(-5150 1575);
DISPLAY 0.617021 (-5150 1575);
PAINT AQUA (-5150 1575);
DISPLAY INVISIBLE (-5150 1575);
FORCEPROP 2 LAST BOM_COST SB
J 0
(-5150 1225);
PAINT MONO (-5150 1225);
DISPLAY INVISIBLE (-5150 1225);
FORCEPROP 2 LAST CDS_LIB dev_discrete
J 0
(-5200 1475);
PAINT ORANGE (-5200 1475);
DISPLAY INVISIBLE (-5200 1475);
FORCEPROP 2 LAST CDS_SEC 1
J 0
(-5150 1675);
PAINT MONO (-5150 1675);
DISPLAY INVISIBLE (-5150 1675);
FORCEPROP 2 LAST $SEC 1
J 0
(-5150 1675);
PAINT MONO (-5150 1675);
DISPLAY INVISIBLE (-5150 1675);
FORCEPROP 1 LAST PATH I53
J 0
(-5150 1625);
DISPLAY 0.978723 (-5150 1625);
PAINT WHITE (-5150 1625);
DISPLAY INVISIBLE (-5150 1625);
FORCEPROP 2 LAST ROOM SB_DECOUPLING
J 0
(-5200 1475);
PAINT WHITE (-5200 1475);
DISPLAY INVISIBLE (-5200 1475);
FORCEADD P3V3_STBY..1
(-4325 5175);
FORCEPROP 3 LASTPIN (-4325 5125) SIG_NAME P3V3_STBY\g
J 0
(-4315 5135);
DISPLAY 0.659574 (-4315 5135);
PAINT MONO (-4315 5135);
DISPLAY INVISIBLE (-4315 5135);
FORCEPROP 1 LAST VOLTAGE 3.3V
J 0
(-4370 5132);
DISPLAY 0.340426 (-4370 5132);
PAINT SKYBLUE (-4370 5132);
DISPLAY INVISIBLE (-4370 5132);
FORCEPROP 2 LAST CDS_LIB mstr_symbols
J 0
(-4325 5175);
PAINT ORANGE (-4325 5175);
DISPLAY INVISIBLE (-4325 5175);
FORCEPROP 1 LAST SIZE 1B
J 0
(-4280 5197);
DISPLAY 0.340426 (-4280 5197);
PAINT GREEN (-4280 5197);
DISPLAY INVISIBLE (-4280 5197);
FORCEPROP 1 LAST BODY_TYPE PLUMBING
J 0
(-4370 5132);
DISPLAY 0.340426 (-4370 5132);
PAINT GREEN (-4370 5132);
DISPLAY INVISIBLE (-4370 5132);
FORCEPROP 1 LAST PATH I54
J 0
(-4280 5177);
DISPLAY 0.340426 (-4280 5177);
PAINT GREEN (-4280 5177);
DISPLAY INVISIBLE (-4280 5177);
FORCEPROP 1 LAST HDL_POWER P3V3_STBY
J 0
(-4625 5050);
DISPLAY 0.872340 (-4625 5050);
PAINT ORANGE (-4625 5050);
DISPLAY INVISIBLE (-4625 5050);
FORCEADD P3V3_STBY..1
(-4375 4250);
FORCEPROP 3 LASTPIN (-4375 4200) SIG_NAME P3V3_STBY\g
J 0
(-4365 4210);
DISPLAY 0.659574 (-4365 4210);
PAINT MONO (-4365 4210);
DISPLAY INVISIBLE (-4365 4210);
FORCEPROP 1 LAST VOLTAGE 3.3V
J 0
(-4420 4207);
DISPLAY 0.340426 (-4420 4207);
PAINT SKYBLUE (-4420 4207);
DISPLAY INVISIBLE (-4420 4207);
FORCEPROP 1 LAST SIZE 1B
J 0
(-4330 4272);
DISPLAY 0.340426 (-4330 4272);
PAINT GREEN (-4330 4272);
DISPLAY INVISIBLE (-4330 4272);
FORCEPROP 2 LAST CDS_LIB mstr_symbols
J 0
(-4375 4250);
PAINT ORANGE (-4375 4250);
DISPLAY INVISIBLE (-4375 4250);
FORCEPROP 1 LAST BODY_TYPE PLUMBING
J 0
(-4420 4207);
DISPLAY 0.340426 (-4420 4207);
PAINT GREEN (-4420 4207);
DISPLAY INVISIBLE (-4420 4207);
FORCEPROP 1 LAST PATH I55
J 0
(-4330 4252);
DISPLAY 0.340426 (-4330 4252);
PAINT GREEN (-4330 4252);
DISPLAY INVISIBLE (-4330 4252);
FORCEPROP 1 LAST HDL_POWER P3V3_STBY
J 0
(-4675 4125);
DISPLAY 0.872340 (-4675 4125);
PAINT ORANGE (-4675 4125);
DISPLAY INVISIBLE (-4675 4125);
FORCEADD P3V3_STBY..1
(-1475 4225);
FORCEPROP 3 LASTPIN (-1475 4175) SIG_NAME P3V3_STBY\g
J 0
(-1465 4185);
DISPLAY 0.659574 (-1465 4185);
PAINT MONO (-1465 4185);
DISPLAY INVISIBLE (-1465 4185);
FORCEPROP 1 LAST VOLTAGE 3.3V
J 0
(-1520 4182);
DISPLAY 0.340426 (-1520 4182);
PAINT SKYBLUE (-1520 4182);
DISPLAY INVISIBLE (-1520 4182);
FORCEPROP 1 LAST SIZE 1B
J 0
(-1430 4247);
DISPLAY 0.340426 (-1430 4247);
PAINT GREEN (-1430 4247);
DISPLAY INVISIBLE (-1430 4247);
FORCEPROP 2 LAST CDS_LIB mstr_symbols
J 0
(-1475 4225);
PAINT ORANGE (-1475 4225);
DISPLAY INVISIBLE (-1475 4225);
FORCEPROP 1 LAST BODY_TYPE PLUMBING
J 0
(-1520 4182);
DISPLAY 0.340426 (-1520 4182);
PAINT GREEN (-1520 4182);
DISPLAY INVISIBLE (-1520 4182);
FORCEPROP 1 LAST PATH I58
J 0
(-1430 4227);
DISPLAY 0.340426 (-1430 4227);
PAINT GREEN (-1430 4227);
DISPLAY INVISIBLE (-1430 4227);
FORCEPROP 1 LAST HDL_POWER P3V3_STBY
J 0
(-1775 4100);
DISPLAY 0.872340 (-1775 4100);
PAINT ORANGE (-1775 4100);
DISPLAY INVISIBLE (-1775 4100);
FORCEADD P3V3_STBY..1
(1125 5200);
FORCEPROP 3 LASTPIN (1125 5150) SIG_NAME P3V3_STBY\g
J 0
(1135 5160);
DISPLAY 0.659574 (1135 5160);
PAINT MONO (1135 5160);
DISPLAY INVISIBLE (1135 5160);
FORCEPROP 1 LAST VOLTAGE 3.3V
J 0
(1080 5157);
DISPLAY 0.340426 (1080 5157);
PAINT SKYBLUE (1080 5157);
DISPLAY INVISIBLE (1080 5157);
FORCEPROP 2 LAST CDS_LIB mstr_symbols
J 0
(1125 5200);
PAINT ORANGE (1125 5200);
DISPLAY INVISIBLE (1125 5200);
FORCEPROP 1 LAST SIZE 1B
J 0
(1170 5222);
DISPLAY 0.340426 (1170 5222);
PAINT GREEN (1170 5222);
DISPLAY INVISIBLE (1170 5222);
FORCEPROP 1 LAST BODY_TYPE PLUMBING
J 0
(1080 5157);
DISPLAY 0.340426 (1080 5157);
PAINT GREEN (1080 5157);
DISPLAY INVISIBLE (1080 5157);
FORCEPROP 1 LAST PATH I59
J 0
(1170 5202);
DISPLAY 0.340426 (1170 5202);
PAINT GREEN (1170 5202);
DISPLAY INVISIBLE (1170 5202);
FORCEPROP 1 LAST HDL_POWER P3V3_STBY
J 0
(825 5075);
DISPLAY 0.872340 (825 5075);
PAINT ORANGE (825 5075);
DISPLAY INVISIBLE (825 5075);
FORCEADD GND..1
(1175 3600);
FORCEPROP 3 LASTPIN (1175 3650) SIG_NAME GND\g
J 0
(1185 3660);
DISPLAY 0.659574 (1185 3660);
PAINT MONO (1185 3660);
DISPLAY INVISIBLE (1185 3660);
FORCEPROP 1 LAST VOLTAGE 0
J 0
(1175 3600);
PAINT SKYBLUE (1175 3600);
DISPLAY INVISIBLE (1175 3600);
FORCEPROP 2 LAST BOM_COST SB
J 0
(1125 3675);
PAINT MONO (1125 3675);
DISPLAY INVISIBLE (1125 3675);
FORCEPROP 1 LAST SIZE 1B
J 0
(1250 3550);
DISPLAY 1.404255 (1250 3550);
PAINT GREEN (1250 3550);
DISPLAY INVISIBLE (1250 3550);
FORCEPROP 2 LAST CDS_LIB mstr_symbols
J 0
(1175 3600);
PAINT ORANGE (1175 3600);
DISPLAY INVISIBLE (1175 3600);
FORCEPROP 1 LAST BODY_TYPE PLUMBING
J 0
(1130 3557);
DISPLAY 0.340426 (1130 3557);
PAINT GREEN (1130 3557);
DISPLAY INVISIBLE (1130 3557);
FORCEPROP 1 LAST PATH I6
J 0
(1250 3600);
DISPLAY 0.872340 (1250 3600);
PAINT AQUA (1250 3600);
DISPLAY INVISIBLE (1250 3600);
FORCEPROP 2 LAST ROOM SB_DECOUPLING
J 0
(700 3675);
PAINT WHITE (700 3675);
DISPLAY INVISIBLE (700 3675);
FORCEPROP 1 LAST HDL_POWER GND
J 0
(1175 3750);
DISPLAY 1.404255 (1175 3750);
PAINT GREEN (1175 3750);
DISPLAY INVISIBLE (1175 3750);
FORCEADD P3V3_STBY..1
(1175 4175);
FORCEPROP 3 LASTPIN (1175 4125) SIG_NAME P3V3_STBY\g
J 0
(1185 4135);
DISPLAY 0.659574 (1185 4135);
PAINT MONO (1185 4135);
DISPLAY INVISIBLE (1185 4135);
FORCEPROP 1 LAST VOLTAGE 3.3V
J 0
(1130 4132);
DISPLAY 0.340426 (1130 4132);
PAINT SKYBLUE (1130 4132);
DISPLAY INVISIBLE (1130 4132);
FORCEPROP 2 LAST CDS_LIB mstr_symbols
J 0
(1175 4175);
PAINT ORANGE (1175 4175);
DISPLAY INVISIBLE (1175 4175);
FORCEPROP 1 LAST SIZE 1B
J 0
(1220 4197);
DISPLAY 0.340426 (1220 4197);
PAINT GREEN (1220 4197);
DISPLAY INVISIBLE (1220 4197);
FORCEPROP 1 LAST BODY_TYPE PLUMBING
J 0
(1130 4132);
DISPLAY 0.340426 (1130 4132);
PAINT GREEN (1130 4132);
DISPLAY INVISIBLE (1130 4132);
FORCEPROP 1 LAST PATH I60
J 0
(1220 4177);
DISPLAY 0.340426 (1220 4177);
PAINT GREEN (1220 4177);
DISPLAY INVISIBLE (1220 4177);
FORCEPROP 1 LAST HDL_POWER P3V3_STBY
J 0
(875 4050);
DISPLAY 0.872340 (875 4050);
PAINT ORANGE (875 4050);
DISPLAY INVISIBLE (875 4050);
FORCEADD P3V3_STBY..1
(650 2925);
FORCEPROP 3 LASTPIN (650 2875) SIG_NAME P3V3_STBY\g
J 0
(660 2885);
DISPLAY 0.659574 (660 2885);
PAINT MONO (660 2885);
DISPLAY INVISIBLE (660 2885);
FORCEPROP 1 LAST VOLTAGE 3.3V
J 0
(605 2882);
DISPLAY 0.340426 (605 2882);
PAINT SKYBLUE (605 2882);
DISPLAY INVISIBLE (605 2882);
FORCEPROP 2 LAST CDS_LIB mstr_symbols
J 0
(650 2925);
PAINT ORANGE (650 2925);
DISPLAY INVISIBLE (650 2925);
FORCEPROP 1 LAST SIZE 1B
J 0
(695 2947);
DISPLAY 0.340426 (695 2947);
PAINT GREEN (695 2947);
DISPLAY INVISIBLE (695 2947);
FORCEPROP 1 LAST BODY_TYPE PLUMBING
J 0
(605 2882);
DISPLAY 0.340426 (605 2882);
PAINT GREEN (605 2882);
DISPLAY INVISIBLE (605 2882);
FORCEPROP 1 LAST PATH I61
J 0
(695 2927);
DISPLAY 0.340426 (695 2927);
PAINT GREEN (695 2927);
DISPLAY INVISIBLE (695 2927);
FORCEPROP 1 LAST HDL_POWER P3V3_STBY
J 0
(350 2800);
DISPLAY 0.872340 (350 2800);
PAINT ORANGE (350 2800);
DISPLAY INVISIBLE (350 2800);
FORCEADD P3V3_STBY..1
(1925 1875);
FORCEPROP 3 LASTPIN (1925 1825) SIG_NAME P3V3_STBY\g
J 0
(1935 1835);
DISPLAY 0.659574 (1935 1835);
PAINT MONO (1935 1835);
DISPLAY INVISIBLE (1935 1835);
FORCEPROP 1 LAST VOLTAGE 3.3V
J 0
(1880 1832);
DISPLAY 0.340426 (1880 1832);
PAINT SKYBLUE (1880 1832);
DISPLAY INVISIBLE (1880 1832);
FORCEPROP 2 LAST CDS_LIB mstr_symbols
J 0
(1925 1875);
PAINT ORANGE (1925 1875);
DISPLAY INVISIBLE (1925 1875);
FORCEPROP 1 LAST SIZE 1B
J 0
(1970 1897);
DISPLAY 0.340426 (1970 1897);
PAINT GREEN (1970 1897);
DISPLAY INVISIBLE (1970 1897);
FORCEPROP 1 LAST BODY_TYPE PLUMBING
J 0
(1880 1832);
DISPLAY 0.340426 (1880 1832);
PAINT GREEN (1880 1832);
DISPLAY INVISIBLE (1880 1832);
FORCEPROP 1 LAST PATH I62
J 0
(1970 1877);
DISPLAY 0.340426 (1970 1877);
PAINT GREEN (1970 1877);
DISPLAY INVISIBLE (1970 1877);
FORCEPROP 1 LAST HDL_POWER P3V3_STBY
J 0
(1625 1750);
DISPLAY 0.872340 (1625 1750);
PAINT ORANGE (1625 1750);
DISPLAY INVISIBLE (1625 1750);
FORCEADD CAP_A..1
(1175 3900);
FORCEPROP 1 LAST LOCATION C2N19
J 0
(1225 4000);
DISPLAY 0.617021 (1225 4000);
PAINT AQUA (1225 4000);
FORCEPROP 1 LAST PART_NUMBER D97712-004
J 0
(1225 3750);
DISPLAY 0.617021 (1225 3750);
PAINT BLUE (1225 3750);
FORCEPROP 1 LAST VALUE 1.0UF
J 0
(1225 3950);
DISPLAY 0.617021 (1225 3950);
PAINT SKYBLUE (1225 3950);
FORCEPROP 1 LAST TOLERANCE 10%
J 0
(1225 3850);
DISPLAY 0.617021 (1225 3850);
PAINT SKYBLUE (1225 3850);
FORCEPROP 1 LAST PACK_TYPE 0402V
J 0
(1225 3700);
DISPLAY 0.617021 (1225 3700);
PAINT SKYBLUE (1225 3700);
FORCEPROP 1 LAST VOLTAGE 6.3V
J 0
(1225 3900);
DISPLAY 0.617021 (1225 3900);
PAINT SKYBLUE (1225 3900);
FORCEPROP 1 LAST MATERIAL X6S
J 0
(1225 3800);
DISPLAY 0.617021 (1225 3800);
PAINT SKYBLUE (1225 3800);
FORCEPROP 1 LASTPIN (1175 4000) $PN 1
J 0
(1185 3980);
DISPLAY 0.617021 (1185 3980);
PAINT WHITE (1185 3980);
FORCEPROP 1 LASTPIN (1175 3800) $PN 2
J 0
(1185 3780);
DISPLAY 0.617021 (1185 3780);
PAINT WHITE (1185 3780);
FORCEPROP 2 LAST CDS_LOCATION C2N19
J 0
(1225 4000);
DISPLAY 0.617021 (1225 4000);
PAINT AQUA (1225 4000);
DISPLAY INVISIBLE (1225 4000);
FORCEPROP 2 LAST BOM_COST SB
J 0
(1225 3650);
PAINT MONO (1225 3650);
DISPLAY INVISIBLE (1225 3650);
FORCEPROP 2 LAST CDS_LIB dev_discrete
J 0
(1175 3900);
PAINT ORANGE (1175 3900);
DISPLAY INVISIBLE (1175 3900);
FORCEPROP 2 LAST CDS_SEC 1
J 0
(1225 4100);
DISPLAY 1.361702 (1225 4100);
PAINT ORANGE (1225 4100);
DISPLAY INVISIBLE (1225 4100);
FORCEPROP 2 LAST $SEC 1
J 0
(1225 4100);
DISPLAY 0.914894 (1225 4100);
PAINT MONO (1225 4100);
DISPLAY INVISIBLE (1225 4100);
FORCEPROP 1 LAST PATH I7
J 0
(1225 4050);
DISPLAY 0.978723 (1225 4050);
PAINT WHITE (1225 4050);
DISPLAY INVISIBLE (1225 4050);
FORCEPROP 2 LAST ROOM SB_DECOUPLING
J 0
(1175 3900);
PAINT WHITE (1175 3900);
DISPLAY INVISIBLE (1175 3900);
FORCEADD CAP..1
(1300 2650);
FORCEPROP 1 LAST LOCATION C2N24
J 0
(1350 2750);
DISPLAY 0.617021 (1350 2750);
PAINT AQUA (1350 2750);
FORCEPROP 1 LAST PART_NUMBER E15431-002
J 0
(1350 2500);
DISPLAY 0.617021 (1350 2500);
PAINT BLUE (1350 2500);
FORCEPROP 1 LAST VALUE 10UF
J 0
(1350 2700);
DISPLAY 0.617021 (1350 2700);
PAINT SKYBLUE (1350 2700);
FORCEPROP 1 LAST TOLERANCE 20%
J 0
(1350 2600);
DISPLAY 0.617021 (1350 2600);
PAINT SKYBLUE (1350 2600);
FORCEPROP 1 LAST PACK_TYPE 0603
J 0
(1350 2450);
DISPLAY 0.617021 (1350 2450);
PAINT SKYBLUE (1350 2450);
FORCEPROP 1 LAST VOLTAGE 6.3V
J 0
(1350 2650);
DISPLAY 0.617021 (1350 2650);
PAINT SKYBLUE (1350 2650);
FORCEPROP 1 LAST MATERIAL X6S
J 0
(1350 2550);
DISPLAY 0.617021 (1350 2550);
PAINT SKYBLUE (1350 2550);
FORCEPROP 1 LASTPIN (1300 2550) $PN 2
J 0
(1310 2530);
DISPLAY 0.617021 (1310 2530);
PAINT WHITE (1310 2530);
FORCEPROP 1 LASTPIN (1300 2750) $PN 1
J 0
(1310 2730);
DISPLAY 0.617021 (1310 2730);
PAINT WHITE (1310 2730);
FORCEPROP 2 LAST CDS_LIB mstr_discrete
J 0
(1300 2650);
PAINT ORANGE (1300 2650);
DISPLAY INVISIBLE (1300 2650);
FORCEPROP 2 LAST BOM_COST SB
J 0
(1350 2400);
PAINT MONO (1350 2400);
DISPLAY INVISIBLE (1350 2400);
FORCEPROP 2 LAST CDS_SEC 1
J 0
(1350 2850);
DISPLAY 1.361702 (1350 2850);
PAINT ORANGE (1350 2850);
DISPLAY INVISIBLE (1350 2850);
FORCEPROP 2 LAST $SEC 1
J 0
(1350 2850);
DISPLAY 0.914894 (1350 2850);
PAINT MONO (1350 2850);
DISPLAY INVISIBLE (1350 2850);
FORCEPROP 2 LAST CDS_LOCATION C2N24
J 0
(1350 2750);
DISPLAY 0.617021 (1350 2750);
PAINT AQUA (1350 2750);
DISPLAY INVISIBLE (1350 2750);
FORCEPROP 1 LAST PATH I8
J 0
(1350 2800);
DISPLAY 0.978723 (1350 2800);
PAINT WHITE (1350 2800);
DISPLAY INVISIBLE (1350 2800);
FORCEPROP 2 LAST ROOM SB_DECOUPLING
J 0
(1300 2650);
PAINT WHITE (1300 2650);
DISPLAY INVISIBLE (1300 2650);
FORCEADD CAP..1
(875 2650);
FORCEPROP 1 LAST LOCATION C2N22
J 0
(925 2750);
DISPLAY 0.617021 (925 2750);
PAINT AQUA (925 2750);
FORCEPROP 1 LAST PART_NUMBER E15431-002
J 0
(925 2500);
DISPLAY 0.617021 (925 2500);
PAINT BLUE (925 2500);
FORCEPROP 1 LAST VALUE 10UF
J 0
(925 2700);
DISPLAY 0.617021 (925 2700);
PAINT SKYBLUE (925 2700);
FORCEPROP 1 LAST TOLERANCE 20%
J 0
(925 2600);
DISPLAY 0.617021 (925 2600);
PAINT SKYBLUE (925 2600);
FORCEPROP 1 LAST PACK_TYPE 0603
J 0
(925 2450);
DISPLAY 0.617021 (925 2450);
PAINT SKYBLUE (925 2450);
FORCEPROP 1 LAST VOLTAGE 6.3V
J 0
(925 2650);
DISPLAY 0.617021 (925 2650);
PAINT SKYBLUE (925 2650);
FORCEPROP 1 LAST MATERIAL X6S
J 0
(925 2550);
DISPLAY 0.617021 (925 2550);
PAINT SKYBLUE (925 2550);
FORCEPROP 1 LASTPIN (875 2550) $PN 2
J 0
(885 2530);
DISPLAY 0.617021 (885 2530);
PAINT WHITE (885 2530);
FORCEPROP 1 LASTPIN (875 2750) $PN 1
J 0
(885 2730);
DISPLAY 0.617021 (885 2730);
PAINT WHITE (885 2730);
FORCEPROP 2 LAST CDS_LIB mstr_discrete
J 0
(875 2650);
PAINT ORANGE (875 2650);
DISPLAY INVISIBLE (875 2650);
FORCEPROP 2 LAST BOM_COST SB
J 0
(925 2400);
PAINT MONO (925 2400);
DISPLAY INVISIBLE (925 2400);
FORCEPROP 2 LAST CDS_SEC 1
J 0
(925 2850);
DISPLAY 1.361702 (925 2850);
PAINT ORANGE (925 2850);
DISPLAY INVISIBLE (925 2850);
FORCEPROP 2 LAST $SEC 1
J 0
(925 2850);
DISPLAY 0.914894 (925 2850);
PAINT MONO (925 2850);
DISPLAY INVISIBLE (925 2850);
FORCEPROP 2 LAST CDS_LOCATION C2N22
J 0
(925 2750);
DISPLAY 0.617021 (925 2750);
PAINT AQUA (925 2750);
DISPLAY INVISIBLE (925 2750);
FORCEPROP 1 LAST PATH I9
J 0
(925 2800);
DISPLAY 0.978723 (925 2800);
PAINT WHITE (925 2800);
DISPLAY INVISIBLE (925 2800);
FORCEPROP 2 LAST ROOM SB_DECOUPLING
J 0
(875 2650);
PAINT WHITE (875 2650);
DISPLAY INVISIBLE (875 2650);
FORCEADD CAD_NOTE..1
(-3100 1225);
FORCEPROP 0 LAST L1 PLACE CAPS BSC
J 0
(-3250 1100);
DISPLAY 1.063830 (-3250 1100);
PAINT WHITE (-3250 1100);
FORCEPROP 0 LAST L2 STYLE NEAR TO PIN.
J 0
(-3250 1025);
DISPLAY 1.063830 (-3250 1025);
PAINT WHITE (-3250 1025);
FORCEPROP 2 LAST CDS_LIB mstr_symbols
J 0
(-3100 1225);
PAINT ORANGE (-3100 1225);
DISPLAY INVISIBLE (-3100 1225);
FORCEPROP 2 LAST BOM_COST SB
J 0
(-3250 1175);
PAINT MONO (-3250 1175);
DISPLAY INVISIBLE (-3250 1175);
FORCEPROP 1 LAST COMMENT_BODY TRUE
J 0
(-3075 1325);
DISPLAY 1.319149 (-3075 1325);
PAINT GREEN (-3075 1325);
DISPLAY INVISIBLE (-3075 1325);
FORCEPROP 2 LAST ROOM SB_DECOUPLING
J 0
(-3250 1175);
PAINT WHITE (-3250 1175);
DISPLAY INVISIBLE (-3250 1175);
FORCEADD CAD_NOTE..1
(-2525 3625);
FORCEPROP 0 LAST L1 PLACE CAPS BSC
J 0
(-2675 3500);
DISPLAY 1.063830 (-2675 3500);
PAINT WHITE (-2675 3500);
FORCEPROP 0 LAST L2 STYLE NEAR TO PIN
J 0
(-2675 3425);
DISPLAY 1.063830 (-2675 3425);
PAINT WHITE (-2675 3425);
FORCEPROP 2 LAST BOM_COST SB
J 0
(-2675 3575);
PAINT MONO (-2675 3575);
DISPLAY INVISIBLE (-2675 3575);
FORCEPROP 2 LAST CDS_LIB mstr_symbols
J 0
(-2525 3625);
PAINT ORANGE (-2525 3625);
DISPLAY INVISIBLE (-2525 3625);
FORCEPROP 1 LAST COMMENT_BODY TRUE
J 0
(-2500 3725);
DISPLAY 1.319149 (-2500 3725);
PAINT GREEN (-2500 3725);
DISPLAY INVISIBLE (-2500 3725);
FORCEPROP 2 LAST ROOM SB_DECOUPLING
J 0
(-2675 3575);
PAINT WHITE (-2675 3575);
DISPLAY INVISIBLE (-2675 3575);
FORCEADD CAD_NOTE..1
(1775 4225);
FORCEPROP 0 LAST L2 STYLE NEAR TO PIN.
J 0
(1625 4025);
DISPLAY 1.063830 (1625 4025);
PAINT WHITE (1625 4025);
FORCEPROP 0 LAST L1 PLACE CAPS BSC
J 0
(1625 4100);
DISPLAY 1.063830 (1625 4100);
PAINT WHITE (1625 4100);
FORCEPROP 2 LAST CDS_LIB mstr_symbols
J 0
(1775 4225);
PAINT ORANGE (1775 4225);
DISPLAY INVISIBLE (1775 4225);
FORCEPROP 2 LAST BOM_COST SB
J 0
(1625 4175);
PAINT MONO (1625 4175);
DISPLAY INVISIBLE (1625 4175);
FORCEPROP 1 LAST COMMENT_BODY TRUE
J 0
(1800 4325);
DISPLAY 1.319149 (1800 4325);
PAINT GREEN (1800 4325);
DISPLAY INVISIBLE (1800 4325);
FORCEPROP 2 LAST ROOM SB_DECOUPLING
J 0
(1625 4175);
PAINT WHITE (1625 4175);
DISPLAY INVISIBLE (1625 4175);
FORCEADD CAD_NOTE..1
(1700 3075);
FORCEPROP 0 LAST L2 EDGE OF THE PKG.
J 0
(1550 2875);
DISPLAY 1.063830 (1550 2875);
PAINT WHITE (1550 2875);
FORCEPROP 0 LAST L1 PLACE CAPS ON THE
J 0
(1550 2950);
DISPLAY 1.063830 (1550 2950);
PAINT WHITE (1550 2950);
FORCEPROP 2 LAST BOM_COST SB
J 0
(1550 3025);
PAINT MONO (1550 3025);
DISPLAY INVISIBLE (1550 3025);
FORCEPROP 2 LAST CDS_LIB mstr_symbols
J 0
(1700 3075);
PAINT ORANGE (1700 3075);
DISPLAY INVISIBLE (1700 3075);
FORCEPROP 1 LAST COMMENT_BODY TRUE
J 0
(1725 3175);
DISPLAY 1.319149 (1725 3175);
PAINT GREEN (1725 3175);
DISPLAY INVISIBLE (1725 3175);
FORCEPROP 2 LAST ROOM SB_DECOUPLING
J 0
(1550 3025);
PAINT WHITE (1550 3025);
DISPLAY INVISIBLE (1550 3025);
FORCEADD DESIGN_NOTE..1
(700 1800);
FORCEPROP 0 LAST L2 DECOUPLING CAPS
J 0
(500 1600);
DISPLAY 1.063830 (500 1600);
PAINT WHITE (500 1600);
FORCEPROP 0 LAST L1 P3V3_DSW
J 0
(500 1675);
DISPLAY 1.063830 (500 1675);
PAINT WHITE (500 1675);
FORCEPROP 2 LAST BOM_COST SB
J 0
(500 1725);
DISPLAY 1.361702 (500 1725);
PAINT ORANGE (500 1725);
DISPLAY INVISIBLE (500 1725);
FORCEPROP 2 LAST CDS_LIB mstr_symbols
J 0
(700 1800);
PAINT ORANGE (700 1800);
DISPLAY INVISIBLE (700 1800);
FORCEPROP 1 LAST COMMENT_BODY TRUE
J 0
(725 1900);
DISPLAY 1.319149 (725 1900);
PAINT ORANGE (725 1900);
DISPLAY INVISIBLE (725 1900);
FORCEPROP 2 LAST ROOM SB_DECOUPLING
J 0
(500 1725);
DISPLAY 1.361702 (500 1725);
PAINT WHITE (500 1725);
DISPLAY INVISIBLE (500 1725);
FORCEADD CAD_NOTE..1
(1750 5175);
FORCEPROP 0 LAST L1 PLACE CAPS ON THE
J 0
(1600 5050);
DISPLAY 1.063830 (1600 5050);
PAINT WHITE (1600 5050);
FORCEPROP 0 LAST L2 EDGE OF THE PKG.
J 0
(1600 4975);
DISPLAY 1.063830 (1600 4975);
PAINT WHITE (1600 4975);
FORCEPROP 2 LAST BOM_COST SB
J 0
(1600 5125);
PAINT MONO (1600 5125);
DISPLAY INVISIBLE (1600 5125);
FORCEPROP 2 LAST CDS_LIB mstr_symbols
J 0
(1750 5175);
PAINT ORANGE (1750 5175);
DISPLAY INVISIBLE (1750 5175);
FORCEPROP 1 LAST COMMENT_BODY TRUE
J 0
(1775 5275);
DISPLAY 1.319149 (1775 5275);
PAINT GREEN (1775 5275);
DISPLAY INVISIBLE (1775 5275);
FORCEPROP 2 LAST ROOM SB_DECOUPLING
J 0
(1600 5125);
PAINT WHITE (1600 5125);
DISPLAY INVISIBLE (1600 5125);
FORCEADD CAD_NOTE..1
(-950 1700);
FORCEPROP 0 LAST L2 NEAR TO PIN.
J 0
(-1100 1500);
DISPLAY 1.063830 (-1100 1500);
PAINT WHITE (-1100 1500);
FORCEPROP 0 LAST L1 PLACE CAP
J 0
(-1100 1575);
DISPLAY 1.063830 (-1100 1575);
PAINT WHITE (-1100 1575);
FORCEPROP 2 LAST CDS_LIB mstr_symbols
J 0
(-950 1700);
PAINT ORANGE (-950 1700);
DISPLAY INVISIBLE (-950 1700);
FORCEPROP 2 LAST BOM_COST SB
J 0
(-1100 1650);
PAINT MONO (-1100 1650);
DISPLAY INVISIBLE (-1100 1650);
FORCEPROP 1 LAST COMMENT_BODY TRUE
J 0
(-925 1800);
DISPLAY 1.319149 (-925 1800);
PAINT GREEN (-925 1800);
DISPLAY INVISIBLE (-925 1800);
FORCEPROP 2 LAST ROOM SB_DECOUPLING
J 0
(-1100 1650);
PAINT WHITE (-1100 1650);
DISPLAY INVISIBLE (-1100 1650);
FORCEADD DESIGN_NOTE..1
(1875 3625);
FORCEPROP 0 LAST L2 DECOUPLING CAPS
J 0
(1675 3425);
DISPLAY 1.063830 (1675 3425);
PAINT WHITE (1675 3425);
FORCEPROP 0 LAST L1 P3V3_STBY
J 0
(1675 3500);
DISPLAY 1.063830 (1675 3500);
PAINT WHITE (1675 3500);
FORCEPROP 2 LAST CDS_LIB mstr_symbols
J 0
(1875 3625);
PAINT ORANGE (1875 3625);
DISPLAY INVISIBLE (1875 3625);
FORCEPROP 2 LAST BOM_COST SB
J 0
(1675 3550);
DISPLAY 1.361702 (1675 3550);
PAINT ORANGE (1675 3550);
DISPLAY INVISIBLE (1675 3550);
FORCEPROP 1 LAST COMMENT_BODY TRUE
J 0
(1900 3725);
DISPLAY 1.319149 (1900 3725);
PAINT ORANGE (1900 3725);
DISPLAY INVISIBLE (1900 3725);
FORCEPROP 2 LAST ROOM SB_DECOUPLING
J 0
(1675 3550);
DISPLAY 1.361702 (1675 3550);
PAINT WHITE (1675 3550);
DISPLAY INVISIBLE (1675 3550);
FORCEADD CAD_NOTE..1
(1775 2200);
FORCEPROP 0 LAST L2 STYLE NEAR TO PIN.
J 0
(1625 2000);
DISPLAY 1.063830 (1625 2000);
PAINT WHITE (1625 2000);
FORCEPROP 0 LAST L1 PLACE CAPS BSC
J 0
(1625 2075);
DISPLAY 1.063830 (1625 2075);
PAINT WHITE (1625 2075);
FORCEPROP 2 LAST BOM_COST SB
J 0
(1625 2150);
PAINT MONO (1625 2150);
DISPLAY INVISIBLE (1625 2150);
FORCEPROP 2 LAST CDS_LIB mstr_symbols
J 0
(1775 2200);
PAINT ORANGE (1775 2200);
DISPLAY INVISIBLE (1775 2200);
FORCEPROP 1 LAST COMMENT_BODY TRUE
J 0
(1800 2300);
DISPLAY 1.319149 (1800 2300);
PAINT GREEN (1800 2300);
DISPLAY INVISIBLE (1800 2300);
FORCEPROP 2 LAST ROOM SB_DECOUPLING
J 0
(1625 2150);
PAINT WHITE (1625 2150);
DISPLAY INVISIBLE (1625 2150);
FORCEADD DESIGN_NOTE..1
(-925 2725);
FORCEPROP 0 LAST L1 VCCRTCEXT: RTC DECOUPLING
J 0
(-1125 2600);
DISPLAY 1.063830 (-1125 2600);
PAINT WHITE (-1125 2600);
FORCEPROP 0 LAST L3 BE DRIVEN
J 0
(-1125 2450);
DISPLAY 1.085106 (-1125 2450);
PAINT WHITE (-1125 2450);
FORCEPROP 0 LAST L2 CAP ONLY, PIN SHOULD NOT
J 0
(-1125 2525);
DISPLAY 1.063830 (-1125 2525);
PAINT WHITE (-1125 2525);
FORCEPROP 2 LAST CDS_LIB mstr_symbols
J 0
(-925 2725);
PAINT ORANGE (-925 2725);
DISPLAY INVISIBLE (-925 2725);
FORCEPROP 2 LAST BOM_COST SB
J 0
(-1125 2650);
DISPLAY 1.361702 (-1125 2650);
PAINT ORANGE (-1125 2650);
DISPLAY INVISIBLE (-1125 2650);
FORCEPROP 1 LAST COMMENT_BODY TRUE
J 0
(-900 2825);
DISPLAY 1.319149 (-900 2825);
PAINT ORANGE (-900 2825);
DISPLAY INVISIBLE (-900 2825);
FORCEPROP 2 LAST ROOM SB_DECOUPLING
J 0
(-1125 2650);
DISPLAY 1.361702 (-1125 2650);
PAINT WHITE (-1125 2650);
DISPLAY INVISIBLE (-1125 2650);
FORCEADD DESIGN_NOTE..1
(-1950 1300);
FORCEPROP 0 LAST L1 P1V8_PCH_STBY
J 0
(-2150 1175);
DISPLAY 1.063830 (-2150 1175);
PAINT WHITE (-2150 1175);
FORCEPROP 0 LAST L2 DECOUPLING CAPS
J 0
(-2150 1100);
DISPLAY 1.063830 (-2150 1100);
PAINT WHITE (-2150 1100);
FORCEPROP 2 LAST CDS_LIB mstr_symbols
J 0
(-1950 1300);
PAINT ORANGE (-1950 1300);
DISPLAY INVISIBLE (-1950 1300);
FORCEPROP 2 LAST BOM_COST SB
J 0
(-2150 1225);
DISPLAY 1.361702 (-2150 1225);
PAINT ORANGE (-2150 1225);
DISPLAY INVISIBLE (-2150 1225);
FORCEPROP 1 LAST COMMENT_BODY TRUE
J 0
(-1925 1400);
DISPLAY 1.319149 (-1925 1400);
PAINT ORANGE (-1925 1400);
DISPLAY INVISIBLE (-1925 1400);
FORCEPROP 2 LAST ROOM SB_DECOUPLING
J 0
(-2150 1225);
DISPLAY 1.361702 (-2150 1225);
PAINT WHITE (-2150 1225);
DISPLAY INVISIBLE (-2150 1225);
FORCEADD DESIGN_NOTE..1
(-1200 3525);
FORCEPROP 0 LAST L1 P3V3_STBY DECOUPLING CAPS
J 0
(-1400 3400);
DISPLAY 1.063830 (-1400 3400);
PAINT WHITE (-1400 3400);
FORCEPROP 2 LAST BOM_COST SB
J 0
(-1400 3450);
DISPLAY 1.361702 (-1400 3450);
PAINT ORANGE (-1400 3450);
DISPLAY INVISIBLE (-1400 3450);
FORCEPROP 2 LAST CDS_LIB mstr_symbols
J 0
(-1200 3525);
PAINT ORANGE (-1200 3525);
DISPLAY INVISIBLE (-1200 3525);
FORCEPROP 1 LAST COMMENT_BODY TRUE
J 0
(-1175 3625);
DISPLAY 1.319149 (-1175 3625);
PAINT ORANGE (-1175 3625);
DISPLAY INVISIBLE (-1175 3625);
FORCEPROP 2 LAST ROOM SB_DECOUPLING
J 0
(-1400 3450);
DISPLAY 1.361702 (-1400 3450);
PAINT WHITE (-1400 3450);
DISPLAY INVISIBLE (-1400 3450);
FORCEADD CAD_NOTE..1
(-1900 5025);
FORCEPROP 0 LAST L1 PLACE CAPS ON THE
J 0
(-2050 4900);
DISPLAY 1.063830 (-2050 4900);
PAINT WHITE (-2050 4900);
FORCEPROP 0 LAST L2 EDGE OF THE PKG.
J 0
(-2050 4825);
DISPLAY 1.063830 (-2050 4825);
PAINT WHITE (-2050 4825);
FORCEPROP 2 LAST BOM_COST SB
J 0
(-2050 4975);
PAINT MONO (-2050 4975);
DISPLAY INVISIBLE (-2050 4975);
FORCEPROP 2 LAST CDS_LIB mstr_symbols
J 0
(-1900 5025);
PAINT ORANGE (-1900 5025);
DISPLAY INVISIBLE (-1900 5025);
FORCEPROP 1 LAST COMMENT_BODY TRUE
J 0
(-1875 5125);
DISPLAY 1.319149 (-1875 5125);
PAINT GREEN (-1875 5125);
DISPLAY INVISIBLE (-1875 5125);
FORCEPROP 2 LAST ROOM SB_DECOUPLING
J 0
(-2050 4975);
PAINT WHITE (-2050 4975);
DISPLAY INVISIBLE (-2050 4975);
FORCEADD CAD_NOTE..1
(-2425 2850);
FORCEPROP 0 LAST L1 PLACE CAPS ON THE
J 0
(-2575 2725);
DISPLAY 1.063830 (-2575 2725);
PAINT WHITE (-2575 2725);
FORCEPROP 0 LAST L2 EDGE OF THE PKG.
J 0
(-2575 2650);
DISPLAY 1.063830 (-2575 2650);
PAINT WHITE (-2575 2650);
FORCEPROP 2 LAST CDS_LIB mstr_symbols
J 0
(-2425 2850);
PAINT ORANGE (-2425 2850);
DISPLAY INVISIBLE (-2425 2850);
FORCEPROP 2 LAST BOM_COST SB
J 0
(-2575 2800);
PAINT MONO (-2575 2800);
DISPLAY INVISIBLE (-2575 2800);
FORCEPROP 1 LAST COMMENT_BODY TRUE
J 0
(-2400 2950);
DISPLAY 1.319149 (-2400 2950);
PAINT GREEN (-2400 2950);
DISPLAY INVISIBLE (-2400 2950);
FORCEPROP 2 LAST ROOM SB_DECOUPLING
J 0
(-2575 2800);
PAINT WHITE (-2575 2800);
DISPLAY INVISIBLE (-2575 2800);
FORCEADD INTEL_CORP_BPAGE..1
(2600 525);
FORCEPROP 1 LAST CDS_CON_LAST_MODIFIED Tue Dec 01 11:52:00 2015
J 0
(1175 850);
PAINT ORANGE (1175 850);
DISPLAY INVISIBLE (1175 850);
FORCEPROP 1 LAST CUSTOM_TXT_CDS <CURRENT_DESIGN_SHEET> OF <TOTAL_DESIGN_SHEETS>
J 0
(2100 550);
PAINT GREEN (2100 550);
FORCEPROP 1 LAST CUSTOM_TXT_CDS <CON_LAST_MODIFIED>
J 0
(675 875);
PAINT GREEN (675 875);
FORCEPROP 2 LAST CUSTOM_TXT_CDS <XR_PAGE_TITLE>
J 0
(-5290 5775);
DISPLAY 0.638298 (-5290 5775);
PAINT PINK (-5290 5775);
DISPLAY INVISIBLE (-5290 5775);
FORCEPROP 1 LAST SCH_ADDRESS3 Santa Clara, CA 95052-8119
J 0
(-1375 550);
DISPLAY 0.617021 (-1375 550);
PAINT GREEN (-1375 550);
FORCEPROP 1 LAST SCH_ADDRESS2 P.O. BOX 58119
J 0
(-1375 600);
DISPLAY 0.617021 (-1375 600);
PAINT GREEN (-1375 600);
FORCEPROP 1 LAST SCH_ADDRESS1 2200 Mission College Blvd.
J 0
(-1375 650);
DISPLAY 0.617021 (-1375 650);
PAINT GREEN (-1375 650);
FORCEPROP 1 LAST SCH_TITLE PCH DECOUPLING 1/3
J 0
(-5350 575);
DISPLAY 1.212766 (-5350 575);
PAINT ORANGE (-5350 575);
FORCEPROP 1 LAST SCH_NUMBER H4694802
J 0
(1300 675);
DISPLAY 1.212766 (1300 675);
PAINT YELLOW (1300 675);
FORCEPROP 1 LAST SCH_DEPT BESD
J 1
(-1850 625);
DISPLAY 1.212766 (-1850 625);
PAINT YELLOW (-1850 625);
FORCEPROP 1 LAST SCH_REV 2.420
J 0
(2350 675);
DISPLAY 0.978723 (2350 675);
PAINT YELLOW (2350 675);
FORCEPROP 2 LAST BOM_COST SB
J 0
(-5275 5825);
PAINT MONO (-5275 5825);
DISPLAY INVISIBLE (-5275 5825);
FORCEPROP 2 LAST PAGE_BORDER TRUE
J 0
(-5290 5775);
DISPLAY 0.851064 (-5290 5775);
PAINT PINK (-5290 5775);
DISPLAY INVISIBLE (-5290 5775);
FORCEPROP 2 LAST CDS_LIB mstr_symbols
J 0
(2600 525);
PAINT MONO (2600 525);
DISPLAY INVISIBLE (2600 525);
FORCEPROP 1 LAST COMMENT_BODY TRUE
J 0
(2612 537);
DISPLAY 0.468085 (2612 537);
PAINT GREEN (2612 537);
DISPLAY INVISIBLE (2612 537);
FORCEPROP 2 LAST ROOM WBG_DECOUPLING
J 0
(-5275 5825);
PAINT MONO (-5275 5825);
DISPLAY INVISIBLE (-5275 5825);
FORCEPROP 2 LAST CDS_XR_PAGE_TITLE CR-130 : @BASEBOARD_FAB2_LIB.BASEBOARD_FAB2(SCH_1):PAGE130
J 0
(-5290 5775);
DISPLAY 0.638298 (-5290 5775);
PAINT PINK (-5290 5775);
DISPLAY INVISIBLE (-5290 5775);
WIRE 16 -1 (1925 1350)(1925 1500);
WIRE 16 -1 (1725 2550)(1725 2425);
WIRE 16 -1 (1300 2425)(1725 2425);
WIRE 16 -1 (1300 2550)(1300 2425);
WIRE 16 -1 (1300 2425)(875 2425);
WIRE 16 -1 (875 2550)(875 2425);
WIRE 16 -1 (650 2425)(875 2425);
WIRE 16 -1 (425 2425)(650 2425);
WIRE 16 -1 (650 2425)(650 2400);
WIRE 16 -1 (425 2550)(425 2425);
WIRE 16 -1 (0 1775)(0 1925);
WIRE 16 -1 (-1475 3675)(-1475 3825);
WIRE 16 -1 (1125 4775)(1125 4903);
WIRE 16 -1 (-1975 2000)(-1975 2125);
WIRE 16 -1 (-1975 1625)(-1975 1800);
WIRE 16 -1 (-2550 4825)(-2550 4700);
WIRE 16 -1 (-2550 4700)(-2975 4700);
WIRE 16 -1 (-2975 4825)(-2975 4700);
WIRE 16 -1 (-2975 4700)(-3375 4700);
WIRE 16 -1 (-3375 4825)(-3375 4700);
WIRE 16 -1 (-3375 4700)(-3775 4700);
WIRE 16 -1 (-3775 4825)(-3775 4700);
WIRE 16 -1 (-3775 4700)(-4175 4700);
WIRE 16 -1 (-4175 4825)(-4175 4700);
WIRE 16 -1 (-4325 4700)(-4175 4700);
WIRE 16 -1 (-4575 4700)(-4325 4700);
WIRE 16 -1 (-4325 4700)(-4325 4625);
WIRE 16 -1 (-4575 4825)(-4575 4700);
WIRE 16 -1 (-3450 3825)(-3450 3700);
WIRE 16 -1 (-3450 3700)(-3825 3700);
WIRE 16 -1 (-3825 3825)(-3825 3700);
WIRE 16 -1 (-3825 3700)(-4200 3700);
WIRE 16 -1 (-4200 3825)(-4200 3700);
WIRE 16 -1 (-4375 3700)(-4200 3700);
WIRE 16 -1 (-4600 3700)(-4375 3700);
WIRE 16 -1 (-4375 3700)(-4375 3625);
WIRE 16 -1 (-4600 3825)(-4600 3700);
WIRE 16 -1 (-3100 2850)(-3100 2925);
WIRE 16 -1 (-3100 2925)(-3525 2925);
WIRE 16 -1 (-3525 2850)(-3525 2925);
WIRE 16 -1 (-3925 2925)(-3525 2925);
WIRE 16 -1 (-3925 2850)(-3925 2925);
WIRE 16 -1 (-4350 2925)(-3925 2925);
WIRE 16 -1 (-4350 2850)(-4350 2925);
WIRE 16 -1 (-4350 2925)(-4725 2925);
WIRE 16 -1 (-4725 2850)(-4725 2925);
WIRE 16 -1 (-4725 2925)(-4850 2925);
WIRE 16 -1 (-4850 2925)(-5150 2925);
WIRE 16 -1 (-4850 2925)(-4850 2975);
WIRE 16 -1 (-5150 2850)(-5150 2925);
WIRE 16 -1 (-3100 2650)(-3100 2525);
WIRE 16 -1 (-3100 2525)(-3525 2525);
WIRE 16 -1 (-3525 2650)(-3525 2525);
WIRE 16 -1 (-3525 2525)(-3925 2525);
WIRE 16 -1 (-3925 2650)(-3925 2525);
WIRE 16 -1 (-4075 2525)(-3925 2525);
WIRE 16 -1 (-4075 2525)(-4350 2525);
WIRE 16 -1 (-4075 2525)(-4075 2475);
WIRE 16 -1 (-4350 2525)(-4725 2525);
WIRE 16 -1 (-4350 2650)(-4350 2525);
WIRE 16 -1 (-4725 2525)(-5150 2525);
WIRE 16 -1 (-4725 2650)(-4725 2525);
WIRE 16 -1 (-5150 2650)(-5150 2525);
WIRE 16 -1 (-5200 1375)(-5200 1250);
WIRE 16 -1 (-5200 1250)(-4775 1250);
WIRE 16 -1 (-4775 1375)(-4775 1250);
WIRE 16 -1 (-4775 1250)(-4350 1250);
WIRE 16 -1 (-4350 1375)(-4350 1250);
WIRE 16 -1 (-4350 1250)(-3975 1250);
WIRE 16 -1 (-3975 1375)(-3975 1250);
WIRE 16 -1 (-3975 1250)(-3750 1250);
WIRE 16 -1 (-3600 1250)(-3750 1250);
WIRE 16 -1 (-3750 1250)(-3750 1200);
WIRE 16 -1 (-3600 1375)(-3600 1250);
WIRE 16 -1 (-3600 1575)(-3600 1650);
WIRE 16 -1 (-3600 1650)(-3975 1650);
WIRE 16 -1 (-3975 1575)(-3975 1650);
WIRE 16 -1 (-4350 1650)(-3975 1650);
WIRE 16 -1 (-4350 1575)(-4350 1650);
WIRE 16 -1 (-4775 1650)(-4350 1650);
WIRE 16 -1 (-4775 1575)(-4775 1650);
WIRE 16 -1 (-4950 1650)(-4775 1650);
WIRE 16 -1 (-5200 1650)(-4950 1650);
WIRE 16 -1 (-4950 1650)(-4950 1700);
WIRE 16 -1 (-5200 1575)(-5200 1650);
WIRE 16 -1 (-2550 5025)(-2550 5100);
WIRE 16 -1 (-2550 5100)(-2975 5100);
WIRE 16 -1 (-2975 5025)(-2975 5100);
WIRE 16 -1 (-2975 5100)(-3375 5100);
WIRE 16 -1 (-3375 5025)(-3375 5100);
WIRE 16 -1 (-3375 5100)(-3775 5100);
WIRE 16 -1 (-3775 5025)(-3775 5100);
WIRE 16 -1 (-3775 5100)(-4175 5100);
WIRE 16 -1 (-4175 5025)(-4175 5100);
WIRE 16 -1 (-4325 5100)(-4175 5100);
WIRE 16 -1 (-4575 5100)(-4325 5100);
WIRE 16 -1 (-4325 5100)(-4325 5125);
WIRE 16 -1 (-4575 5025)(-4575 5100);
WIRE 16 -1 (-3450 4025)(-3450 4100);
WIRE 16 -1 (-3450 4100)(-3825 4100);
WIRE 16 -1 (-3825 4025)(-3825 4100);
WIRE 16 -1 (-3825 4100)(-4200 4100);
WIRE 16 -1 (-4200 4025)(-4200 4100);
WIRE 16 -1 (-4375 4100)(-4200 4100);
WIRE 16 -1 (-4375 4100)(-4600 4100);
WIRE 16 -1 (-4375 4100)(-4375 4200);
WIRE 16 -1 (-4600 4025)(-4600 4100);
WIRE 16 -1 (-1475 4025)(-1475 4175);
WIRE 16 -1 (1125 5150)(1125 5103);
WIRE 16 -1 (1175 3650)(1175 3800);
WIRE 16 -1 (1175 4000)(1175 4125);
WIRE 16 -1 (1725 2825)(1725 2750);
WIRE 16 -1 (1300 2825)(1725 2825);
WIRE 16 -1 (1300 2825)(1300 2750);
WIRE 16 -1 (1300 2825)(875 2825);
WIRE 16 -1 (875 2750)(875 2825);
WIRE 16 -1 (650 2825)(875 2825);
WIRE 16 -1 (425 2825)(650 2825);
WIRE 16 -1 (650 2825)(650 2875);
WIRE 16 -1 (425 2750)(425 2825);
WIRE 16 -1 (1925 1700)(1925 1825);
WIRE 16 273 (2456 5393)(806 5393);
WIRE 16 273 (2456 5393)(2456 3318);
WIRE 16 273 (806 5393)(806 3318);
WIRE 16 273 (806 3318)(2456 3318);
WIRE 16 273 (-5250 3325)(700 3325);
WIRE 16 273 (700 5375)(700 3325);
WIRE 16 273 (700 5375)(-5250 5375);
WIRE 16 273 (-5250 5375)(-5250 3350);
WIRE 16 273 (-1350 3175)(-1350 950);
WIRE 16 273 (-1350 3175)(-5275 3175);
WIRE 16 273 (-5275 950)(-1350 950);
WIRE 16 273 (-5275 3175)(-5275 950);
WIRE 16 273 (175 950)(175 3175);
WIRE 16 273 (-1250 950)(175 950);
WIRE 16 273 (175 3175)(-1250 3175);
WIRE 16 273 (-1250 3175)(-1250 950);
WIRE 16 -1 (-575 2275)(0 2275);
FORCEPROP 2 LAST SIG_NAME A_PVCCRTC_EXT_CAP
J 0
(-550 2285);
DISPLAY 0.617021 (-550 2285);
PAINT ORANGE (-550 2285);
WIRE 16 -1 (0 2125)(0 2275);
WIRE 16 273 (2475 950)(2475 3175);
WIRE 16 273 (2475 950)(275 950);
WIRE 16 273 (2475 3175)(275 3175);
WIRE 16 273 (275 3175)(275 950);
DOT 1 (-4175 5100);
DOT 1 (1300 2825);
DOT 1 (875 2825);
DOT 1 (650 2825);
DOT 1 (875 2425);
DOT 1 (650 2425);
DOT 1 (-2975 5100);
DOT 1 (-2975 4700);
DOT 1 (-3375 5100);
DOT 1 (-3775 5100);
DOT 1 (-4325 5100);
DOT 1 (-3825 4100);
DOT 1 (-3825 3700);
DOT 1 (-4200 4100);
DOT 1 (-4375 4100);
DOT 1 (-4375 3700);
DOT 1 (-3525 2925);
DOT 1 (-3925 2925);
DOT 1 (-4350 2925);
DOT 1 (-4725 2925);
DOT 1 (-4850 2925);
DOT 1 (-3925 2525);
DOT 1 (-3525 2525);
DOT 1 (-3975 1650);
DOT 1 (-4075 2525);
DOT 1 (-4350 2525);
DOT 1 (-4350 1650);
DOT 1 (-3750 1250);
DOT 1 (-3975 1250);
DOT 1 (-4350 1250);
DOT 1 (-4725 2525);
DOT 1 (-4775 1650);
DOT 1 (-4950 1650);
DOT 1 (-4775 1250);
DOT 1 (-4175 4700);
DOT 1 (-4325 4700);
DOT 1 (-3375 4700);
DOT 1 (-3775 4700);
DOT 1 (1300 2425);
DOT 1 (-4200 3700);
FORCENOTE
BOM_COST=SB
(-3425 750) 0;
DISPLAY LEFT (-3425 750);
DISPLAY 2.148936 (-3425 750);
PAINT PURPLE (-3425 750);
FORCENOTE
ROOM=SB_DECOUPLING
(-5100 750) 0;
DISPLAY LEFT (-5100 750);
DISPLAY 2.148936 (-5100 750);
PAINT PURPLE (-5100 750);
QUIT
